FILE_TYPE = MACRO_DRAWING;
SET COLOR_WIRE YELLOW;
SET COLOR_PROP MONO;
SET COLOR_DOT WHITE;
SET COLOR_ARC YELLOW;
SET COLOR_BODY GREEN;
SET COLOR_NOTE MONO;
SET PROP_DISPLAY VALUE;
SET PAGE_NUMBER P93;
FORCEADD OFFPAGE..5
(1600 800);
FORCEPROP 2 LAST $XR0 93 
J 0
(1346 800);
DISPLAY 0.638298 (1346 800);
PAINT MONO (1346 800);
FORCEPROP 2 LAST PATH I100
J 0
(1650 875);
DISPLAY 1.021277 (1650 875);
PAINT ORANGE (1650 875);
DISPLAY INVISIBLE (1650 875);
FORCEPROP 1 LAST COMMENT_BODY TRUE
J 0
(1700 725);
DISPLAY 0.872340 (1700 725);
PAINT GREEN (1700 725);
DISPLAY INVISIBLE (1700 725);
FORCEPROP 2 LAST CDS_LIB mstr_standard
J 0
(1600 800);
PAINT ORANGE (1600 800);
DISPLAY INVISIBLE (1600 800);
FORCEPROP 1 LAST OFFPAGE TRUE
J 0
(1925 675);
DISPLAY 0.872340 (1925 675);
PAINT GREEN (1925 675);
DISPLAY INVISIBLE (1925 675);
FORCEADD OFFPAGE..4
(1475 3600);
FORCEPROP 2 LAST $XR0 93 
J 0
(1661 3600);
DISPLAY 0.638298 (1661 3600);
PAINT MONO (1661 3600);
FORCEPROP 2 LAST PATH I101
J 0
(1650 3675);
DISPLAY 1.021277 (1650 3675);
PAINT ORANGE (1650 3675);
DISPLAY INVISIBLE (1650 3675);
FORCEPROP 1 LAST OFFPAGE TRUE
J 0
(1800 3475);
DISPLAY 0.872340 (1800 3475);
PAINT GREEN (1800 3475);
DISPLAY INVISIBLE (1800 3475);
FORCEPROP 2 LAST CDS_LIB mstr_standard
J 0
(1475 3600);
PAINT ORANGE (1475 3600);
DISPLAY INVISIBLE (1475 3600);
FORCEPROP 1 LAST COMMENT_BODY TRUE
J 0
(1450 3500);
DISPLAY 0.872340 (1450 3500);
PAINT GREEN (1450 3500);
DISPLAY INVISIBLE (1450 3500);
FORCEADD RES..1
(-825 2175);
FORCEPROP 1 LASTPIN (-725 2175) $PN 2
J 0
(-763 2187);
DISPLAY 0.617021 (-763 2187);
PAINT ORANGE (-763 2187);
FORCEPROP 1 LASTPIN (-925 2175) $PN 1
J 0
(-913 2187);
DISPLAY 0.617021 (-913 2187);
PAINT ORANGE (-913 2187);
FORCEPROP 1 LAST VALUE 0.0
J 2
(-675 2125);
DISPLAY 0.617021 (-675 2125);
PAINT SKYBLUE (-675 2125);
FORCEPROP 1 LAST LOCATION R2T68
J 0
(-950 2125);
DISPLAY 0.617021 (-950 2125);
PAINT AQUA (-950 2125);
FORCEPROP 1 LAST TOLERANCE 5%
J 0
(-625 2125);
DISPLAY 0.617021 (-625 2125);
PAINT SKYBLUE (-625 2125);
FORCEPROP 1 LAST WATTAGE 1/16W
J 2
(-400 2125);
DISPLAY 0.617021 (-400 2125);
PAINT SKYBLUE (-400 2125);
FORCEPROP 1 LAST MATERIAL CHIP
J 0
(-950 2075);
DISPLAY 0.617021 (-950 2075);
PAINT SKYBLUE (-950 2075);
FORCEPROP 1 LAST PART_NUMBER G21497-005
J 0
(-800 2075);
DISPLAY 0.617021 (-800 2075);
PAINT BLUE (-800 2075);
FORCEPROP 1 LAST PACK_TYPE 0402
J 0
(-525 2075);
DISPLAY 0.617021 (-525 2075);
PAINT SKYBLUE (-525 2075);
FORCEPROP 1 LAST PATH I102
J 0
(-875 2325);
DISPLAY 0.978723 (-875 2325);
PAINT WHITE (-875 2325);
DISPLAY INVISIBLE (-875 2325);
FORCEPROP 2 LAST SEC 1
J 0
(-875 2375);
DISPLAY 0.680851 (-875 2375);
PAINT MONO (-875 2375);
DISPLAY INVISIBLE (-875 2375);
FORCEPROP 2 LAST SEC_TYPE 0402
J 0
(-875 2375);
DISPLAY 1.021277 (-875 2375);
PAINT ORANGE (-875 2375);
DISPLAY INVISIBLE (-875 2375);
FORCEPROP 2 LAST CDS_LIB mstr_discrete
J 0
(-825 2175);
PAINT ORANGE (-825 2175);
DISPLAY INVISIBLE (-825 2175);
FORCEADD RES..1
(-825 2300);
FORCEPROP 1 LASTPIN (-925 2300) $PN 1
J 0
(-913 2312);
DISPLAY 0.617021 (-913 2312);
PAINT ORANGE (-913 2312);
FORCEPROP 1 LASTPIN (-725 2300) $PN 2
J 0
(-763 2312);
DISPLAY 0.617021 (-763 2312);
PAINT ORANGE (-763 2312);
FORCEPROP 1 LAST LOCATION R2T60
J 0
(-950 2500);
DISPLAY 0.617021 (-950 2500);
PAINT AQUA (-950 2500);
FORCEPROP 1 LAST TOLERANCE 5%
J 0
(-950 2450);
DISPLAY 0.617021 (-950 2450);
PAINT SKYBLUE (-950 2450);
FORCEPROP 1 LAST MATERIAL CHIP
J 0
(-950 2400);
DISPLAY 0.617021 (-950 2400);
PAINT SKYBLUE (-950 2400);
FORCEPROP 1 LAST VALUE 0.0
J 2
(-700 2500);
DISPLAY 0.617021 (-700 2500);
PAINT SKYBLUE (-700 2500);
FORCEPROP 1 LAST WATTAGE 1/16W
J 2
(-700 2450);
DISPLAY 0.617021 (-700 2450);
PAINT SKYBLUE (-700 2450);
FORCEPROP 1 LAST PACK_TYPE 0402
J 0
(-800 2400);
DISPLAY 0.617021 (-800 2400);
PAINT SKYBLUE (-800 2400);
FORCEPROP 1 LAST PART_NUMBER G21497-005
J 0
(-950 2350);
DISPLAY 0.617021 (-950 2350);
PAINT BLUE (-950 2350);
FORCEPROP 2 LAST CDS_LIB mstr_discrete
J 0
(-825 2300);
PAINT ORANGE (-825 2300);
DISPLAY INVISIBLE (-825 2300);
FORCEPROP 2 LAST SEC_TYPE 0402
J 0
(-875 2500);
DISPLAY 1.021277 (-875 2500);
PAINT ORANGE (-875 2500);
DISPLAY INVISIBLE (-875 2500);
FORCEPROP 2 LAST SEC 1
J 0
(-875 2500);
DISPLAY 0.680851 (-875 2500);
PAINT MONO (-875 2500);
DISPLAY INVISIBLE (-875 2500);
FORCEPROP 1 LAST PATH I103
J 0
(-875 2450);
DISPLAY 0.978723 (-875 2450);
PAINT WHITE (-875 2450);
DISPLAY INVISIBLE (-875 2450);
FORCEADD PVCCIO_CPU1..1
(-2200 2800);
FORCEPROP 3 LASTPIN (-2200 2750) SIG_NAME PVCCIO_CPU1\g
J 0
(-2190 2760);
DISPLAY 0.659574 (-2190 2760);
PAINT MONO (-2190 2760);
DISPLAY INVISIBLE (-2190 2760);
FORCEPROP 1 LAST HDL_POWER PVCCIO_CPU1
J 1
(-2200 2850);
DISPLAY 0.872340 (-2200 2850);
PAINT GREEN (-2200 2850);
DISPLAY INVISIBLE (-2200 2850);
FORCEPROP 1 LAST PATH I105
J 0
(-2150 2825);
DISPLAY 0.872340 (-2150 2825);
PAINT AQUA (-2150 2825);
DISPLAY INVISIBLE (-2150 2825);
FORCEPROP 2 LAST CDS_LIB mstr_symbols
J 0
(-2200 2800);
PAINT ORANGE (-2200 2800);
DISPLAY INVISIBLE (-2200 2800);
FORCEPROP 1 LAST VOLTAGE 1.1V
J 0
(-2245 2757);
DISPLAY 0.340426 (-2245 2757);
PAINT SKYBLUE (-2245 2757);
DISPLAY INVISIBLE (-2245 2757);
FORCEPROP 1 LAST BODY_TYPE PLUMBING
J 0
(-2245 2757);
DISPLAY 0.340426 (-2245 2757);
PAINT GREEN (-2245 2757);
DISPLAY INVISIBLE (-2245 2757);
FORCEADD RES..2
(-2200 2500);
FORCEPROP 1 LAST WATTAGE 1/16W
J 0
(-2160 2475);
DISPLAY 0.617021 (-2160 2475);
PAINT SKYBLUE (-2160 2475);
FORCEPROP 1 LAST PACK_TYPE 0402
J 0
(-2160 2325);
DISPLAY 0.617021 (-2160 2325);
PAINT SKYBLUE (-2160 2325);
FORCEPROP 1 LAST VALUE 150.0
J 0
(-2155 2575);
DISPLAY 0.617021 (-2155 2575);
PAINT SKYBLUE (-2155 2575);
FORCEPROP 1 LAST LOCATION R7P28
J 0
(-2155 2625);
DISPLAY 0.617021 (-2155 2625);
PAINT AQUA (-2155 2625);
FORCEPROP 1 LAST PART_NUMBER G21796-009
J 0
(-2160 2375);
DISPLAY 0.617021 (-2160 2375);
PAINT BLUE (-2160 2375);
FORCEPROP 1 LAST MATERIAL CHIP
J 0
(-2160 2425);
DISPLAY 0.617021 (-2160 2425);
PAINT SKYBLUE (-2160 2425);
FORCEPROP 1 LASTPIN (-2200 2600) $PN 1
J 0
(-2195 2562);
DISPLAY 0.617021 (-2195 2562);
PAINT ORANGE (-2195 2562);
FORCEPROP 1 LAST TOLERANCE 1%
J 0
(-2155 2525);
DISPLAY 0.617021 (-2155 2525);
PAINT SKYBLUE (-2155 2525);
FORCEPROP 1 LASTPIN (-2200 2400) $PN 2
J 0
(-2195 2410);
DISPLAY 0.617021 (-2195 2410);
PAINT ORANGE (-2195 2410);
FORCEPROP 1 LAST PATH I106
J 0
(-2150 2675);
DISPLAY 0.978723 (-2150 2675);
PAINT WHITE (-2150 2675);
DISPLAY INVISIBLE (-2150 2675);
FORCEPROP 2 LAST SEC_TYPE 0402
J 0
(-2150 2725);
DISPLAY 1.021277 (-2150 2725);
PAINT ORANGE (-2150 2725);
DISPLAY INVISIBLE (-2150 2725);
FORCEPROP 2 LAST SEC 1
J 0
(-2150 2725);
DISPLAY 0.680851 (-2150 2725);
PAINT MONO (-2150 2725);
DISPLAY INVISIBLE (-2150 2725);
FORCEPROP 2 LAST CDS_LOCATION R7P28
J 0
(-2155 2625);
DISPLAY 0.617021 (-2155 2625);
PAINT AQUA (-2155 2625);
DISPLAY INVISIBLE (-2155 2625);
FORCEPROP 2 LAST CDS_LIB mstr_discrete
J 0
(-2200 2500);
PAINT MONO (-2200 2500);
DISPLAY INVISIBLE (-2200 2500);
FORCEPROP 2 LAST BOM_COST PROC_SIDEBAND
J 0
(-2200 2500);
PAINT MONO (-2200 2500);
DISPLAY INVISIBLE (-2200 2500);
FORCEPROP 2 LAST ROOM PROC_SIDEBAND
J 0
(-2175 2275);
PAINT ORANGE (-2175 2275);
DISPLAY INVISIBLE (-2175 2275);
FORCEADD RES..2
(-1100 1900);
FORCEPROP 1 LAST PACK_TYPE 0402
J 0
(-1060 1725);
DISPLAY 0.617021 (-1060 1725);
PAINT SKYBLUE (-1060 1725);
FORCEPROP 1 LAST PART_NUMBER G21497-005
J 0
(-1060 1775);
DISPLAY 0.617021 (-1060 1775);
PAINT BLUE (-1060 1775);
FORCEPROP 1 LASTPIN (-1100 1800) $PN 2
J 0
(-1095 1810);
DISPLAY 0.617021 (-1095 1810);
PAINT ORANGE (-1095 1810);
FORCEPROP 1 LAST WATTAGE 1/16W
J 0
(-1060 1875);
DISPLAY 0.617021 (-1060 1875);
PAINT SKYBLUE (-1060 1875);
FORCEPROP 1 LAST TOLERANCE 5%
J 0
(-1055 1925);
DISPLAY 0.617021 (-1055 1925);
PAINT SKYBLUE (-1055 1925);
FORCEPROP 1 LAST VALUE 0.0
J 0
(-1055 1975);
DISPLAY 0.617021 (-1055 1975);
PAINT SKYBLUE (-1055 1975);
FORCEPROP 1 LAST MATERIAL EMPTY
J 0
(-1060 1825);
DISPLAY 0.617021 (-1060 1825);
PAINT RED (-1060 1825);
FORCEPROP 1 LASTPIN (-1100 2000) $PN 1
J 0
(-1095 1962);
DISPLAY 0.617021 (-1095 1962);
PAINT ORANGE (-1095 1962);
FORCEPROP 1 LAST LOCATION R2T59
J 0
(-1055 2025);
DISPLAY 0.617021 (-1055 2025);
PAINT AQUA (-1055 2025);
FORCEPROP 1 LAST PATH I107
J 0
(-1050 2075);
DISPLAY 0.978723 (-1050 2075);
PAINT WHITE (-1050 2075);
DISPLAY INVISIBLE (-1050 2075);
FORCEPROP 2 LAST SEC 1
J 0
(-1050 2125);
DISPLAY 0.680851 (-1050 2125);
PAINT MONO (-1050 2125);
DISPLAY INVISIBLE (-1050 2125);
FORCEPROP 2 LAST SEC_TYPE 0402
J 0
(-1050 2125);
DISPLAY 1.021277 (-1050 2125);
PAINT ORANGE (-1050 2125);
DISPLAY INVISIBLE (-1050 2125);
FORCEPROP 2 LAST CDS_LIB mstr_discrete
J 0
(-1100 1900);
PAINT ORANGE (-1100 1900);
DISPLAY INVISIBLE (-1100 1900);
FORCEADD RES..2
(-1400 1900);
FORCEPROP 1 LAST LOCATION R2T69
J 0
(-1355 2025);
DISPLAY 0.617021 (-1355 2025);
PAINT AQUA (-1355 2025);
FORCEPROP 1 LAST WATTAGE 1/16W
J 0
(-1360 1875);
DISPLAY 0.617021 (-1360 1875);
PAINT SKYBLUE (-1360 1875);
FORCEPROP 1 LAST PACK_TYPE 0402
J 0
(-1360 1725);
DISPLAY 0.617021 (-1360 1725);
PAINT SKYBLUE (-1360 1725);
FORCEPROP 1 LAST VALUE 0.0
J 0
(-1355 1975);
DISPLAY 0.617021 (-1355 1975);
PAINT SKYBLUE (-1355 1975);
FORCEPROP 1 LAST PART_NUMBER G21497-005
J 0
(-1360 1775);
DISPLAY 0.617021 (-1360 1775);
PAINT BLUE (-1360 1775);
FORCEPROP 1 LAST MATERIAL EMPTY
J 0
(-1360 1825);
DISPLAY 0.617021 (-1360 1825);
PAINT RED (-1360 1825);
FORCEPROP 1 LAST TOLERANCE 5%
J 0
(-1355 1925);
DISPLAY 0.617021 (-1355 1925);
PAINT SKYBLUE (-1355 1925);
FORCEPROP 1 LASTPIN (-1400 2000) $PN 1
J 0
(-1395 1962);
DISPLAY 0.617021 (-1395 1962);
PAINT ORANGE (-1395 1962);
FORCEPROP 1 LASTPIN (-1400 1800) $PN 2
J 0
(-1395 1810);
DISPLAY 0.617021 (-1395 1810);
PAINT ORANGE (-1395 1810);
FORCEPROP 1 LAST PATH I108
J 0
(-1350 2075);
DISPLAY 0.978723 (-1350 2075);
PAINT WHITE (-1350 2075);
DISPLAY INVISIBLE (-1350 2075);
FORCEPROP 2 LAST SEC 1
J 0
(-1350 2125);
DISPLAY 0.680851 (-1350 2125);
PAINT MONO (-1350 2125);
DISPLAY INVISIBLE (-1350 2125);
FORCEPROP 2 LAST SEC_TYPE 0402
J 0
(-1350 2125);
DISPLAY 1.021277 (-1350 2125);
PAINT ORANGE (-1350 2125);
DISPLAY INVISIBLE (-1350 2125);
FORCEPROP 2 LAST CDS_LIB mstr_discrete
J 0
(-1400 1900);
PAINT ORANGE (-1400 1900);
DISPLAY INVISIBLE (-1400 1900);
FORCEADD RES..2
(2025 2225);
FORCEPROP 1 LAST TOLERANCE 5%
J 0
(2070 2250);
DISPLAY 0.617021 (2070 2250);
PAINT SKYBLUE (2070 2250);
FORCEPROP 1 LAST PART_NUMBER G21497-005
J 0
(2065 2100);
DISPLAY 0.617021 (2065 2100);
PAINT BLUE (2065 2100);
FORCEPROP 1 LAST PACK_TYPE 0402
J 0
(2065 2050);
DISPLAY 0.617021 (2065 2050);
PAINT SKYBLUE (2065 2050);
FORCEPROP 1 LAST MATERIAL EMPTY
J 0
(2065 2150);
DISPLAY 0.617021 (2065 2150);
PAINT RED (2065 2150);
FORCEPROP 1 LASTPIN (2025 2125) $PN 2
J 0
(2030 2135);
DISPLAY 0.617021 (2030 2135);
PAINT ORANGE (2030 2135);
FORCEPROP 1 LAST WATTAGE 1/16W
J 0
(2065 2200);
DISPLAY 0.617021 (2065 2200);
PAINT SKYBLUE (2065 2200);
FORCEPROP 1 LAST LOCATION R2T71
J 0
(2070 2350);
DISPLAY 0.617021 (2070 2350);
PAINT AQUA (2070 2350);
FORCEPROP 1 LAST VALUE 0.0
J 0
(2070 2300);
DISPLAY 0.617021 (2070 2300);
PAINT SKYBLUE (2070 2300);
FORCEPROP 1 LASTPIN (2025 2325) $PN 1
J 0
(2030 2287);
DISPLAY 0.617021 (2030 2287);
PAINT ORANGE (2030 2287);
FORCEPROP 1 LAST PATH I109
J 0
(2075 2400);
DISPLAY 0.978723 (2075 2400);
PAINT WHITE (2075 2400);
DISPLAY INVISIBLE (2075 2400);
FORCEPROP 2 LAST SEC 1
J 0
(2075 2450);
DISPLAY 0.680851 (2075 2450);
PAINT MONO (2075 2450);
DISPLAY INVISIBLE (2075 2450);
FORCEPROP 2 LAST SEC_TYPE 0402
J 0
(2075 2450);
DISPLAY 1.021277 (2075 2450);
PAINT ORANGE (2075 2450);
DISPLAY INVISIBLE (2075 2450);
FORCEPROP 2 LAST CDS_LIB mstr_discrete
J 0
(2025 2225);
PAINT ORANGE (2025 2225);
DISPLAY INVISIBLE (2025 2225);
FORCEADD RES..2
(2400 2225);
FORCEPROP 1 LAST WATTAGE 1/16W
J 0
(2440 2200);
DISPLAY 0.617021 (2440 2200);
PAINT SKYBLUE (2440 2200);
FORCEPROP 1 LAST MATERIAL EMPTY
J 0
(2440 2150);
DISPLAY 0.617021 (2440 2150);
PAINT RED (2440 2150);
FORCEPROP 1 LAST PART_NUMBER G21497-005
J 0
(2440 2100);
DISPLAY 0.617021 (2440 2100);
PAINT BLUE (2440 2100);
FORCEPROP 1 LAST PACK_TYPE 0402
J 0
(2440 2050);
DISPLAY 0.617021 (2440 2050);
PAINT SKYBLUE (2440 2050);
FORCEPROP 1 LAST LOCATION R7D43
J 0
(2445 2350);
DISPLAY 0.617021 (2445 2350);
PAINT AQUA (2445 2350);
FORCEPROP 1 LASTPIN (2400 2325) $PN 1
J 0
(2405 2287);
DISPLAY 0.617021 (2405 2287);
PAINT ORANGE (2405 2287);
FORCEPROP 1 LAST VALUE 0.0
J 0
(2445 2300);
DISPLAY 0.617021 (2445 2300);
PAINT SKYBLUE (2445 2300);
FORCEPROP 1 LAST TOLERANCE 5%
J 0
(2445 2250);
DISPLAY 0.617021 (2445 2250);
PAINT SKYBLUE (2445 2250);
FORCEPROP 1 LASTPIN (2400 2125) $PN 2
J 0
(2405 2135);
DISPLAY 0.617021 (2405 2135);
PAINT ORANGE (2405 2135);
FORCEPROP 1 LAST PATH I110
J 0
(2450 2400);
DISPLAY 0.978723 (2450 2400);
PAINT WHITE (2450 2400);
DISPLAY INVISIBLE (2450 2400);
FORCEPROP 2 LAST SEC 1
J 0
(2450 2450);
DISPLAY 0.680851 (2450 2450);
PAINT MONO (2450 2450);
DISPLAY INVISIBLE (2450 2450);
FORCEPROP 2 LAST SEC_TYPE 0402
J 0
(2450 2450);
DISPLAY 1.021277 (2450 2450);
PAINT ORANGE (2450 2450);
DISPLAY INVISIBLE (2450 2450);
FORCEPROP 2 LAST CDS_LIB mstr_discrete
J 0
(2400 2225);
PAINT ORANGE (2400 2225);
DISPLAY INVISIBLE (2400 2225);
FORCEADD RES..1
(1875 3350);
FORCEPROP 1 LAST PART_NUMBER G21497-005
J 0
(1750 3300);
DISPLAY 0.617021 (1750 3300);
PAINT BLUE (1750 3300);
FORCEPROP 1 LASTPIN (1975 3350) $PN 2
J 0
(1937 3362);
DISPLAY 0.617021 (1937 3362);
PAINT ORANGE (1937 3362);
FORCEPROP 1 LASTPIN (1775 3350) $PN 1
J 0
(1787 3362);
DISPLAY 0.617021 (1787 3362);
PAINT ORANGE (1787 3362);
FORCEPROP 1 LAST LOCATION R2T65
J 0
(1750 3400);
DISPLAY 0.617021 (1750 3400);
PAINT AQUA (1750 3400);
FORCEPROP 1 LAST VALUE 0.0
J 0
(1925 3400);
DISPLAY 0.617021 (1925 3400);
PAINT SKYBLUE (1925 3400);
FORCEPROP 1 LAST TOLERANCE 5%
J 0
(2025 3400);
DISPLAY 0.617021 (2025 3400);
PAINT SKYBLUE (2025 3400);
FORCEPROP 1 LAST WATTAGE 1/16W
J 0
(2125 3400);
DISPLAY 0.617021 (2125 3400);
PAINT SKYBLUE (2125 3400);
FORCEPROP 1 LAST MATERIAL CHIP
J 0
(2275 3400);
DISPLAY 0.617021 (2275 3400);
PAINT SKYBLUE (2275 3400);
FORCEPROP 1 LAST PACK_TYPE 0402
J 0
(2025 3300);
DISPLAY 0.617021 (2025 3300);
PAINT SKYBLUE (2025 3300);
FORCEPROP 2 LAST SEC_TYPE 0402
J 0
(1825 3550);
DISPLAY 1.021277 (1825 3550);
PAINT ORANGE (1825 3550);
DISPLAY INVISIBLE (1825 3550);
FORCEPROP 2 LAST CDS_LIB mstr_discrete
J 0
(1875 3350);
PAINT ORANGE (1875 3350);
DISPLAY INVISIBLE (1875 3350);
FORCEPROP 2 LAST SEC 1
J 0
(1825 3550);
DISPLAY 0.680851 (1825 3550);
PAINT MONO (1825 3550);
DISPLAY INVISIBLE (1825 3550);
FORCEPROP 1 LAST PATH I111
J 0
(1825 3500);
DISPLAY 0.978723 (1825 3500);
PAINT WHITE (1825 3500);
DISPLAY INVISIBLE (1825 3500);
FORCEADD RES..1
(1875 3100);
FORCEPROP 1 LAST LOCATION R2T66
J 0
(1750 3150);
DISPLAY 0.617021 (1750 3150);
PAINT AQUA (1750 3150);
FORCEPROP 1 LASTPIN (1775 3100) $PN 1
J 0
(1787 3112);
DISPLAY 0.617021 (1787 3112);
PAINT ORANGE (1787 3112);
FORCEPROP 1 LASTPIN (1975 3100) $PN 2
J 0
(1937 3112);
DISPLAY 0.617021 (1937 3112);
PAINT ORANGE (1937 3112);
FORCEPROP 1 LAST VALUE 0.0
J 2
(1975 3150);
DISPLAY 0.617021 (1975 3150);
PAINT SKYBLUE (1975 3150);
FORCEPROP 1 LAST TOLERANCE 5%
J 0
(2025 3150);
DISPLAY 0.617021 (2025 3150);
PAINT SKYBLUE (2025 3150);
FORCEPROP 1 LAST WATTAGE 1/16W
J 2
(2250 3150);
DISPLAY 0.617021 (2250 3150);
PAINT SKYBLUE (2250 3150);
FORCEPROP 1 LAST MATERIAL CHIP
J 0
(2275 3150);
DISPLAY 0.617021 (2275 3150);
PAINT SKYBLUE (2275 3150);
FORCEPROP 1 LAST PART_NUMBER G21497-005
J 0
(1750 3050);
DISPLAY 0.617021 (1750 3050);
PAINT BLUE (1750 3050);
FORCEPROP 1 LAST PACK_TYPE 0402
J 0
(2025 3050);
DISPLAY 0.617021 (2025 3050);
PAINT SKYBLUE (2025 3050);
FORCEPROP 2 LAST SEC 1
J 0
(1825 3300);
DISPLAY 0.680851 (1825 3300);
PAINT MONO (1825 3300);
DISPLAY INVISIBLE (1825 3300);
FORCEPROP 2 LAST SEC_TYPE 0402
J 0
(1825 3300);
DISPLAY 1.021277 (1825 3300);
PAINT ORANGE (1825 3300);
DISPLAY INVISIBLE (1825 3300);
FORCEPROP 2 LAST CDS_LIB mstr_discrete
J 0
(1875 3100);
PAINT ORANGE (1875 3100);
DISPLAY INVISIBLE (1875 3100);
FORCEPROP 1 LAST PATH I112
J 0
(1825 3250);
DISPLAY 0.978723 (1825 3250);
PAINT WHITE (1825 3250);
DISPLAY INVISIBLE (1825 3250);
FORCEADD RES..1
(1875 2850);
FORCEPROP 1 LAST PACK_TYPE 0402
J 0
(2050 2800);
DISPLAY 0.617021 (2050 2800);
PAINT SKYBLUE (2050 2800);
FORCEPROP 1 LAST PART_NUMBER G21497-005
J 0
(1750 2800);
DISPLAY 0.617021 (1750 2800);
PAINT BLUE (1750 2800);
FORCEPROP 1 LAST MATERIAL CHIP
J 0
(2275 2900);
DISPLAY 0.617021 (2275 2900);
PAINT SKYBLUE (2275 2900);
FORCEPROP 1 LAST WATTAGE 1/16W
J 2
(2250 2900);
DISPLAY 0.617021 (2250 2900);
PAINT SKYBLUE (2250 2900);
FORCEPROP 1 LAST TOLERANCE 5%
J 0
(2025 2900);
DISPLAY 0.617021 (2025 2900);
PAINT SKYBLUE (2025 2900);
FORCEPROP 1 LASTPIN (1975 2850) $PN 2
J 0
(1937 2862);
DISPLAY 0.617021 (1937 2862);
PAINT ORANGE (1937 2862);
FORCEPROP 1 LAST VALUE 0.0
J 2
(1975 2900);
DISPLAY 0.617021 (1975 2900);
PAINT SKYBLUE (1975 2900);
FORCEPROP 1 LAST LOCATION R2T67
J 0
(1750 2900);
DISPLAY 0.617021 (1750 2900);
PAINT AQUA (1750 2900);
FORCEPROP 1 LASTPIN (1775 2850) $PN 1
J 0
(1787 2862);
DISPLAY 0.617021 (1787 2862);
PAINT ORANGE (1787 2862);
FORCEPROP 2 LAST SEC 1
J 0
(1825 3050);
DISPLAY 0.680851 (1825 3050);
PAINT MONO (1825 3050);
DISPLAY INVISIBLE (1825 3050);
FORCEPROP 2 LAST SEC_TYPE 0402
J 0
(1825 3050);
DISPLAY 1.021277 (1825 3050);
PAINT ORANGE (1825 3050);
DISPLAY INVISIBLE (1825 3050);
FORCEPROP 2 LAST CDS_LIB mstr_discrete
J 0
(1875 2850);
PAINT ORANGE (1875 2850);
DISPLAY INVISIBLE (1875 2850);
FORCEPROP 1 LAST PATH I113
J 0
(1825 3000);
DISPLAY 0.978723 (1825 3000);
PAINT WHITE (1825 3000);
DISPLAY INVISIBLE (1825 3000);
FORCEADD RES..1
(1875 2575);
FORCEPROP 1 LAST PART_NUMBER G21497-005
J 0
(1750 2525);
DISPLAY 0.617021 (1750 2525);
PAINT BLUE (1750 2525);
FORCEPROP 1 LAST TOLERANCE 5%
J 0
(2025 2625);
DISPLAY 0.617021 (2025 2625);
PAINT SKYBLUE (2025 2625);
FORCEPROP 1 LAST WATTAGE 1/16W
J 2
(2250 2625);
DISPLAY 0.617021 (2250 2625);
PAINT SKYBLUE (2250 2625);
FORCEPROP 1 LAST VALUE 0.0
J 2
(1975 2625);
DISPLAY 0.617021 (1975 2625);
PAINT SKYBLUE (1975 2625);
FORCEPROP 1 LASTPIN (1975 2575) $PN 2
J 0
(1937 2587);
DISPLAY 0.617021 (1937 2587);
PAINT ORANGE (1937 2587);
FORCEPROP 1 LASTPIN (1775 2575) $PN 1
J 0
(1787 2587);
DISPLAY 0.617021 (1787 2587);
PAINT ORANGE (1787 2587);
FORCEPROP 1 LAST LOCATION R7D41
J 0
(1750 2625);
DISPLAY 0.617021 (1750 2625);
PAINT AQUA (1750 2625);
FORCEPROP 1 LAST MATERIAL CHIP
J 0
(2275 2625);
DISPLAY 0.617021 (2275 2625);
PAINT SKYBLUE (2275 2625);
FORCEPROP 1 LAST PACK_TYPE 0402
J 0
(2050 2525);
DISPLAY 0.617021 (2050 2525);
PAINT SKYBLUE (2050 2525);
FORCEPROP 2 LAST SEC_TYPE 0402
J 0
(1825 2775);
DISPLAY 1.021277 (1825 2775);
PAINT ORANGE (1825 2775);
DISPLAY INVISIBLE (1825 2775);
FORCEPROP 2 LAST CDS_LIB mstr_discrete
J 0
(1875 2575);
PAINT ORANGE (1875 2575);
DISPLAY INVISIBLE (1875 2575);
FORCEPROP 2 LAST SEC 1
J 0
(1825 2775);
DISPLAY 0.680851 (1825 2775);
PAINT MONO (1825 2775);
DISPLAY INVISIBLE (1825 2775);
FORCEPROP 1 LAST PATH I114
J 0
(1825 2725);
DISPLAY 0.978723 (1825 2725);
PAINT WHITE (1825 2725);
DISPLAY INVISIBLE (1825 2725);
FORCEADD OFFPAGE..2
(-1325 1450);
FORCEPROP 2 LAST $XR0 145 
J 0
(-1136 1450);
DISPLAY 0.638298 (-1136 1450);
PAINT MONO (-1136 1450);
FORCEPROP 1 LAST OFFPAGE TRUE
J 0
(-1000 1325);
DISPLAY 0.872340 (-1000 1325);
PAINT GREEN (-1000 1325);
DISPLAY INVISIBLE (-1000 1325);
FORCEPROP 2 LAST PATH I115
J 0
(-1150 1525);
DISPLAY 1.021277 (-1150 1525);
PAINT ORANGE (-1150 1525);
DISPLAY INVISIBLE (-1150 1525);
FORCEPROP 2 LAST CDS_LIB mstr_standard
J 0
(-1325 1450);
PAINT ORANGE (-1325 1450);
DISPLAY INVISIBLE (-1325 1450);
FORCEPROP 1 LAST COMMENT_BODY TRUE
J 0
(-1370 1355);
DISPLAY 0.872340 (-1370 1355);
PAINT GREEN (-1370 1355);
DISPLAY INVISIBLE (-1370 1355);
FORCEADD OFFPAGE..2
(-1325 1050);
FORCEPROP 2 LAST $XR0 145 
J 0
(-1136 1050);
DISPLAY 0.638298 (-1136 1050);
PAINT MONO (-1136 1050);
FORCEPROP 1 LAST OFFPAGE TRUE
J 0
(-1000 925);
DISPLAY 0.872340 (-1000 925);
PAINT GREEN (-1000 925);
DISPLAY INVISIBLE (-1000 925);
FORCEPROP 2 LAST PATH I116
J 0
(-1150 1125);
DISPLAY 1.021277 (-1150 1125);
PAINT ORANGE (-1150 1125);
DISPLAY INVISIBLE (-1150 1125);
FORCEPROP 2 LAST CDS_LIB mstr_standard
J 0
(-1325 1050);
PAINT ORANGE (-1325 1050);
DISPLAY INVISIBLE (-1325 1050);
FORCEPROP 1 LAST COMMENT_BODY TRUE
J 0
(-1370 955);
DISPLAY 0.872340 (-1370 955);
PAINT GREEN (-1370 955);
DISPLAY INVISIBLE (-1370 955);
FORCEADD OFFPAGE..2
(-1325 675);
FORCEPROP 2 LAST $XR0 145 
J 0
(-1136 675);
DISPLAY 0.638298 (-1136 675);
PAINT MONO (-1136 675);
FORCEPROP 1 LAST OFFPAGE TRUE
J 0
(-1000 550);
DISPLAY 0.872340 (-1000 550);
PAINT GREEN (-1000 550);
DISPLAY INVISIBLE (-1000 550);
FORCEPROP 2 LAST PATH I117
J 0
(-1150 750);
DISPLAY 1.021277 (-1150 750);
PAINT ORANGE (-1150 750);
DISPLAY INVISIBLE (-1150 750);
FORCEPROP 2 LAST CDS_LIB mstr_standard
J 0
(-1325 675);
PAINT ORANGE (-1325 675);
DISPLAY INVISIBLE (-1325 675);
FORCEPROP 1 LAST COMMENT_BODY TRUE
J 0
(-1370 580);
DISPLAY 0.872340 (-1370 580);
PAINT GREEN (-1370 580);
DISPLAY INVISIBLE (-1370 580);
FORCEADD OFFPAGE..2
(-1325 275);
FORCEPROP 2 LAST $XR0 145 
J 0
(-1136 275);
DISPLAY 0.638298 (-1136 275);
PAINT MONO (-1136 275);
FORCEPROP 1 LAST OFFPAGE TRUE
J 0
(-1000 150);
DISPLAY 0.872340 (-1000 150);
PAINT GREEN (-1000 150);
DISPLAY INVISIBLE (-1000 150);
FORCEPROP 2 LAST PATH I118
J 0
(-1150 350);
DISPLAY 1.021277 (-1150 350);
PAINT ORANGE (-1150 350);
DISPLAY INVISIBLE (-1150 350);
FORCEPROP 2 LAST CDS_LIB mstr_standard
J 0
(-1325 275);
PAINT ORANGE (-1325 275);
DISPLAY INVISIBLE (-1325 275);
FORCEPROP 1 LAST COMMENT_BODY TRUE
J 0
(-1370 180);
DISPLAY 0.872340 (-1370 180);
PAINT GREEN (-1370 180);
DISPLAY INVISIBLE (-1370 180);
FORCEADD RES..1
(-2225 1450);
FORCEPROP 1 LAST PACK_TYPE 0402
J 0
(-2125 1400);
DISPLAY 0.617021 (-2125 1400);
PAINT SKYBLUE (-2125 1400);
FORCEPROP 1 LAST PART_NUMBER G21497-005
J 0
(-2375 1550);
DISPLAY 0.617021 (-2375 1550);
PAINT BLUE (-2375 1550);
FORCEPROP 1 LASTPIN (-2125 1450) $PN 2
J 0
(-2163 1462);
DISPLAY 0.617021 (-2163 1462);
PAINT ORANGE (-2163 1462);
FORCEPROP 1 LAST MATERIAL CHIP
J 0
(-2225 1400);
DISPLAY 0.617021 (-2225 1400);
PAINT SKYBLUE (-2225 1400);
FORCEPROP 1 LAST LOCATION R8F38
J 0
(-2275 1500);
DISPLAY 0.617021 (-2275 1500);
PAINT AQUA (-2275 1500);
FORCEPROP 1 LAST TOLERANCE 5%
J 0
(-2300 1400);
DISPLAY 0.617021 (-2300 1400);
PAINT SKYBLUE (-2300 1400);
FORCEPROP 1 LASTPIN (-2325 1450) $PN 1
J 0
(-2313 1462);
DISPLAY 0.617021 (-2313 1462);
PAINT ORANGE (-2313 1462);
FORCEPROP 1 LAST WATTAGE 1/16W
J 2
(-2325 1400);
DISPLAY 0.617021 (-2325 1400);
PAINT SKYBLUE (-2325 1400);
FORCEPROP 1 LAST VALUE 0.0
J 2
(-2325 1450);
DISPLAY 0.617021 (-2325 1450);
PAINT SKYBLUE (-2325 1450);
FORCEPROP 1 LAST PATH I119
J 0
(-2275 1600);
DISPLAY 0.978723 (-2275 1600);
PAINT WHITE (-2275 1600);
DISPLAY INVISIBLE (-2275 1600);
FORCEPROP 2 LAST SEC 1
J 0
(-2275 1650);
DISPLAY 0.680851 (-2275 1650);
PAINT MONO (-2275 1650);
DISPLAY INVISIBLE (-2275 1650);
FORCEPROP 2 LAST SEC_TYPE 0402
J 0
(-2275 1650);
DISPLAY 1.021277 (-2275 1650);
PAINT ORANGE (-2275 1650);
DISPLAY INVISIBLE (-2275 1650);
FORCEPROP 2 LAST CDS_LIB mstr_discrete
J 0
(-2225 1450);
PAINT ORANGE (-2225 1450);
DISPLAY INVISIBLE (-2225 1450);
FORCEADD OFFPAGE..1
(-3175 1450);
FORCEPROP 2 LAST $XR0 93 
J 0
(-3396 1450);
DISPLAY 0.638298 (-3396 1450);
PAINT MONO (-3396 1450);
FORCEPROP 1 LAST OFFPAGE TRUE
J 0
(-2850 1325);
DISPLAY 0.872340 (-2850 1325);
PAINT GREEN (-2850 1325);
DISPLAY INVISIBLE (-2850 1325);
FORCEPROP 1 LAST COMMENT_BODY TRUE
J 0
(-3050 1350);
DISPLAY 0.872340 (-3050 1350);
PAINT GREEN (-3050 1350);
DISPLAY INVISIBLE (-3050 1350);
FORCEPROP 2 LAST PATH I120
J 0
(-3125 1525);
DISPLAY 1.021277 (-3125 1525);
PAINT ORANGE (-3125 1525);
DISPLAY INVISIBLE (-3125 1525);
FORCEPROP 2 LAST CDS_LIB mstr_standard
J 0
(-3175 1450);
PAINT ORANGE (-3175 1450);
DISPLAY INVISIBLE (-3175 1450);
FORCEADD RES..1
(-2225 1050);
FORCEPROP 1 LAST PACK_TYPE 0402
J 0
(-2125 1000);
DISPLAY 0.617021 (-2125 1000);
PAINT SKYBLUE (-2125 1000);
FORCEPROP 1 LASTPIN (-2125 1050) $PN 2
J 0
(-2163 1062);
DISPLAY 0.617021 (-2163 1062);
PAINT ORANGE (-2163 1062);
FORCEPROP 1 LAST LOCATION R2T64
J 0
(-2275 1100);
DISPLAY 0.617021 (-2275 1100);
PAINT AQUA (-2275 1100);
FORCEPROP 1 LASTPIN (-2325 1050) $PN 1
J 0
(-2313 1062);
DISPLAY 0.617021 (-2313 1062);
PAINT ORANGE (-2313 1062);
FORCEPROP 1 LAST PART_NUMBER G21497-005
J 0
(-2375 1150);
DISPLAY 0.617021 (-2375 1150);
PAINT BLUE (-2375 1150);
FORCEPROP 1 LAST VALUE 0.0
J 2
(-2325 1050);
DISPLAY 0.617021 (-2325 1050);
PAINT SKYBLUE (-2325 1050);
FORCEPROP 1 LAST WATTAGE 1/16W
J 2
(-2325 1000);
DISPLAY 0.617021 (-2325 1000);
PAINT SKYBLUE (-2325 1000);
FORCEPROP 1 LAST MATERIAL CHIP
J 0
(-2225 1000);
DISPLAY 0.617021 (-2225 1000);
PAINT SKYBLUE (-2225 1000);
FORCEPROP 1 LAST TOLERANCE 5%
J 0
(-2300 1000);
DISPLAY 0.617021 (-2300 1000);
PAINT SKYBLUE (-2300 1000);
FORCEPROP 2 LAST SEC_TYPE 0402
J 0
(-2275 1250);
DISPLAY 1.021277 (-2275 1250);
PAINT ORANGE (-2275 1250);
DISPLAY INVISIBLE (-2275 1250);
FORCEPROP 1 LAST PATH I121
J 0
(-2275 1200);
DISPLAY 0.978723 (-2275 1200);
PAINT WHITE (-2275 1200);
DISPLAY INVISIBLE (-2275 1200);
FORCEPROP 2 LAST SEC 1
J 0
(-2275 1250);
DISPLAY 0.680851 (-2275 1250);
PAINT MONO (-2275 1250);
DISPLAY INVISIBLE (-2275 1250);
FORCEPROP 2 LAST CDS_LIB mstr_discrete
J 0
(-2225 1050);
PAINT ORANGE (-2225 1050);
DISPLAY INVISIBLE (-2225 1050);
FORCEADD RES..1
(-2225 675);
FORCEPROP 1 LAST PACK_TYPE 0402
J 0
(-2125 625);
DISPLAY 0.617021 (-2125 625);
PAINT SKYBLUE (-2125 625);
FORCEPROP 1 LASTPIN (-2125 675) $PN 2
J 0
(-2163 687);
DISPLAY 0.617021 (-2163 687);
PAINT ORANGE (-2163 687);
FORCEPROP 1 LAST MATERIAL CHIP
J 0
(-2225 625);
DISPLAY 0.617021 (-2225 625);
PAINT SKYBLUE (-2225 625);
FORCEPROP 1 LAST LOCATION R1T36
J 0
(-2275 725);
DISPLAY 0.617021 (-2275 725);
PAINT AQUA (-2275 725);
FORCEPROP 1 LAST TOLERANCE 5%
J 0
(-2300 625);
DISPLAY 0.617021 (-2300 625);
PAINT SKYBLUE (-2300 625);
FORCEPROP 1 LASTPIN (-2325 675) $PN 1
J 0
(-2313 687);
DISPLAY 0.617021 (-2313 687);
PAINT ORANGE (-2313 687);
FORCEPROP 1 LAST PART_NUMBER G21497-005
J 0
(-2375 775);
DISPLAY 0.617021 (-2375 775);
PAINT BLUE (-2375 775);
FORCEPROP 1 LAST VALUE 0.0
J 2
(-2325 675);
DISPLAY 0.617021 (-2325 675);
PAINT SKYBLUE (-2325 675);
FORCEPROP 1 LAST WATTAGE 1/16W
J 2
(-2325 625);
DISPLAY 0.617021 (-2325 625);
PAINT SKYBLUE (-2325 625);
FORCEPROP 2 LAST SEC 1
J 0
(-2275 875);
DISPLAY 0.680851 (-2275 875);
PAINT MONO (-2275 875);
DISPLAY INVISIBLE (-2275 875);
FORCEPROP 2 LAST SEC_TYPE 0402
J 0
(-2275 875);
DISPLAY 1.021277 (-2275 875);
PAINT ORANGE (-2275 875);
DISPLAY INVISIBLE (-2275 875);
FORCEPROP 1 LAST PATH I122
J 0
(-2275 825);
DISPLAY 0.978723 (-2275 825);
PAINT WHITE (-2275 825);
DISPLAY INVISIBLE (-2275 825);
FORCEPROP 2 LAST CDS_LIB mstr_discrete
J 0
(-2225 675);
PAINT ORANGE (-2225 675);
DISPLAY INVISIBLE (-2225 675);
FORCEADD RES..1
(-2225 275);
FORCEPROP 1 LAST PACK_TYPE 0402
J 0
(-2125 225);
DISPLAY 0.617021 (-2125 225);
PAINT SKYBLUE (-2125 225);
FORCEPROP 1 LASTPIN (-2125 275) $PN 2
J 0
(-2163 287);
DISPLAY 0.617021 (-2163 287);
PAINT ORANGE (-2163 287);
FORCEPROP 1 LAST LOCATION R1T37
J 0
(-2275 325);
DISPLAY 0.617021 (-2275 325);
PAINT AQUA (-2275 325);
FORCEPROP 1 LAST MATERIAL CHIP
J 0
(-2225 225);
DISPLAY 0.617021 (-2225 225);
PAINT SKYBLUE (-2225 225);
FORCEPROP 1 LAST TOLERANCE 5%
J 0
(-2300 225);
DISPLAY 0.617021 (-2300 225);
PAINT SKYBLUE (-2300 225);
FORCEPROP 1 LASTPIN (-2325 275) $PN 1
J 0
(-2313 287);
DISPLAY 0.617021 (-2313 287);
PAINT ORANGE (-2313 287);
FORCEPROP 1 LAST PART_NUMBER G21497-005
J 0
(-2375 375);
DISPLAY 0.617021 (-2375 375);
PAINT BLUE (-2375 375);
FORCEPROP 1 LAST VALUE 0.0
J 2
(-2325 275);
DISPLAY 0.617021 (-2325 275);
PAINT SKYBLUE (-2325 275);
FORCEPROP 1 LAST WATTAGE 1/16W
J 2
(-2325 225);
DISPLAY 0.617021 (-2325 225);
PAINT SKYBLUE (-2325 225);
FORCEPROP 2 LAST SEC_TYPE 0402
J 0
(-2275 475);
DISPLAY 1.021277 (-2275 475);
PAINT ORANGE (-2275 475);
DISPLAY INVISIBLE (-2275 475);
FORCEPROP 1 LAST PATH I123
J 0
(-2275 425);
DISPLAY 0.978723 (-2275 425);
PAINT WHITE (-2275 425);
DISPLAY INVISIBLE (-2275 425);
FORCEPROP 2 LAST SEC 1
J 0
(-2275 475);
DISPLAY 0.680851 (-2275 475);
PAINT MONO (-2275 475);
DISPLAY INVISIBLE (-2275 475);
FORCEPROP 2 LAST CDS_LIB mstr_discrete
J 0
(-2225 275);
PAINT ORANGE (-2225 275);
DISPLAY INVISIBLE (-2225 275);
FORCEADD OFFPAGE..1
(-3175 1050);
FORCEPROP 2 LAST $XR0 93 
J 0
(-3396 1050);
DISPLAY 0.638298 (-3396 1050);
PAINT MONO (-3396 1050);
FORCEPROP 1 LAST OFFPAGE TRUE
J 0
(-2850 925);
DISPLAY 0.872340 (-2850 925);
PAINT GREEN (-2850 925);
DISPLAY INVISIBLE (-2850 925);
FORCEPROP 1 LAST COMMENT_BODY TRUE
J 0
(-3050 950);
DISPLAY 0.872340 (-3050 950);
PAINT GREEN (-3050 950);
DISPLAY INVISIBLE (-3050 950);
FORCEPROP 2 LAST CDS_LIB mstr_standard
J 0
(-3175 1050);
PAINT ORANGE (-3175 1050);
DISPLAY INVISIBLE (-3175 1050);
FORCEPROP 2 LAST PATH I124
J 0
(-3125 1125);
DISPLAY 1.021277 (-3125 1125);
PAINT ORANGE (-3125 1125);
DISPLAY INVISIBLE (-3125 1125);
FORCEADD OFFPAGE..1
(-3175 675);
FORCEPROP 2 LAST $XR0 93 
J 0
(-3396 675);
DISPLAY 0.638298 (-3396 675);
PAINT MONO (-3396 675);
FORCEPROP 1 LAST OFFPAGE TRUE
J 0
(-2850 550);
DISPLAY 0.872340 (-2850 550);
PAINT GREEN (-2850 550);
DISPLAY INVISIBLE (-2850 550);
FORCEPROP 1 LAST COMMENT_BODY TRUE
J 0
(-3050 575);
DISPLAY 0.872340 (-3050 575);
PAINT GREEN (-3050 575);
DISPLAY INVISIBLE (-3050 575);
FORCEPROP 2 LAST PATH I125
J 0
(-3125 750);
DISPLAY 1.021277 (-3125 750);
PAINT ORANGE (-3125 750);
DISPLAY INVISIBLE (-3125 750);
FORCEPROP 2 LAST CDS_LIB mstr_standard
J 0
(-3175 675);
PAINT ORANGE (-3175 675);
DISPLAY INVISIBLE (-3175 675);
FORCEADD OFFPAGE..1
(-3175 275);
FORCEPROP 2 LAST $XR0 93 
J 0
(-3396 275);
DISPLAY 0.638298 (-3396 275);
PAINT MONO (-3396 275);
FORCEPROP 1 LAST OFFPAGE TRUE
J 0
(-2850 150);
DISPLAY 0.872340 (-2850 150);
PAINT GREEN (-2850 150);
DISPLAY INVISIBLE (-2850 150);
FORCEPROP 1 LAST COMMENT_BODY TRUE
J 0
(-3050 175);
DISPLAY 0.872340 (-3050 175);
PAINT GREEN (-3050 175);
DISPLAY INVISIBLE (-3050 175);
FORCEPROP 2 LAST CDS_LIB mstr_standard
J 0
(-3175 275);
PAINT ORANGE (-3175 275);
DISPLAY INVISIBLE (-3175 275);
FORCEPROP 2 LAST PATH I126
J 0
(-3125 350);
DISPLAY 1.021277 (-3125 350);
PAINT ORANGE (-3125 350);
DISPLAY INVISIBLE (-3125 350);
FORCEADD RES..2
(3700 425);
FORCEPROP 1 LAST PART_NUMBER G21796-026
J 0
(3740 300);
DISPLAY 0.617021 (3740 300);
PAINT BLUE (3740 300);
FORCEPROP 1 LASTPIN (3700 325) $PN 2
J 0
(3705 335);
DISPLAY 0.617021 (3705 335);
PAINT ORANGE (3705 335);
FORCEPROP 1 LAST LOCATION R2T50
J 0
(3745 550);
DISPLAY 0.617021 (3745 550);
PAINT AQUA (3745 550);
FORCEPROP 1 LASTPIN (3700 525) $PN 1
J 0
(3705 487);
DISPLAY 0.617021 (3705 487);
PAINT ORANGE (3705 487);
FORCEPROP 1 LAST VALUE 1.00K
J 0
(3745 500);
DISPLAY 0.617021 (3745 500);
PAINT SKYBLUE (3745 500);
FORCEPROP 1 LAST WATTAGE 1/16W
J 0
(3740 400);
DISPLAY 0.617021 (3740 400);
PAINT SKYBLUE (3740 400);
FORCEPROP 1 LAST MATERIAL CHIP
J 0
(3740 350);
DISPLAY 0.617021 (3740 350);
PAINT SKYBLUE (3740 350);
FORCEPROP 1 LAST PACK_TYPE 0402
J 0
(3740 250);
DISPLAY 0.617021 (3740 250);
PAINT SKYBLUE (3740 250);
FORCEPROP 1 LAST TOLERANCE 1%
J 0
(3745 450);
DISPLAY 0.617021 (3745 450);
PAINT SKYBLUE (3745 450);
FORCEPROP 2 LAST ROOM PROC_SIDEBAND
J 0
(3650 575);
PAINT PEACH (3650 575);
DISPLAY INVISIBLE (3650 575);
FORCEPROP 1 LAST PATH I127
J 0
(3750 600);
DISPLAY 0.978723 (3750 600);
PAINT WHITE (3750 600);
DISPLAY INVISIBLE (3750 600);
FORCEPROP 2 LAST CDS_LOCATION R2T50
J 0
(3745 550);
DISPLAY 0.617021 (3745 550);
PAINT AQUA (3745 550);
DISPLAY INVISIBLE (3745 550);
FORCEPROP 2 LAST SEC 1
J 0
(3750 650);
DISPLAY 0.680851 (3750 650);
PAINT MONO (3750 650);
DISPLAY INVISIBLE (3750 650);
FORCEPROP 2 LAST SEC_TYPE 0402
J 0
(3750 650);
DISPLAY 1.021277 (3750 650);
PAINT ORANGE (3750 650);
DISPLAY INVISIBLE (3750 650);
FORCEPROP 2 LAST BOM_COST PROC
J 0
(3700 425);
PAINT MONO (3700 425);
DISPLAY INVISIBLE (3700 425);
FORCEPROP 2 LAST CDS_LIB mstr_discrete
J 0
(3700 425);
PAINT MONO (3700 425);
DISPLAY INVISIBLE (3700 425);
FORCEADD GND..1
(3700 225);
FORCEPROP 3 LASTPIN (3700 275) SIG_NAME GND\g
J 0
(3710 285);
DISPLAY 0.659574 (3710 285);
PAINT MONO (3710 285);
DISPLAY INVISIBLE (3710 285);
FORCEPROP 1 LAST HDL_POWER GND
J 0
(3700 375);
DISPLAY 1.170213 (3700 375);
PAINT GREEN (3700 375);
DISPLAY INVISIBLE (3700 375);
FORCEPROP 1 LAST PATH I128
J 0
(3775 225);
DISPLAY 0.872340 (3775 225);
PAINT AQUA (3775 225);
DISPLAY INVISIBLE (3775 225);
FORCEPROP 2 LAST CDS_LIB mstr_symbols
J 0
(3700 225);
PAINT MONO (3700 225);
DISPLAY INVISIBLE (3700 225);
FORCEPROP 1 LAST VOLTAGE 0
J 0
(3700 225);
PAINT SKYBLUE (3700 225);
DISPLAY INVISIBLE (3700 225);
FORCEPROP 1 LAST BODY_TYPE PLUMBING
J 0
(3655 182);
DISPLAY 0.340426 (3655 182);
PAINT GREEN (3655 182);
DISPLAY INVISIBLE (3655 182);
FORCEPROP 1 LAST SIZE 1B
J 0
(3775 175);
DISPLAY 1.170213 (3775 175);
PAINT GREEN (3775 175);
DISPLAY INVISIBLE (3775 175);
FORCEADD OFFPAGE..4
(1475 3500);
FORCEPROP 2 LAST $XR0 93 
J 0
(1661 3500);
DISPLAY 0.638298 (1661 3500);
PAINT MONO (1661 3500);
FORCEPROP 2 LAST PATH I129
J 0
(1650 3575);
DISPLAY 1.021277 (1650 3575);
PAINT ORANGE (1650 3575);
DISPLAY INVISIBLE (1650 3575);
FORCEPROP 1 LAST OFFPAGE TRUE
J 0
(1800 3375);
DISPLAY 0.872340 (1800 3375);
PAINT GREEN (1800 3375);
DISPLAY INVISIBLE (1800 3375);
FORCEPROP 2 LAST CDS_LIB mstr_standard
J 0
(1475 3500);
PAINT ORANGE (1475 3500);
DISPLAY INVISIBLE (1475 3500);
FORCEPROP 1 LAST COMMENT_BODY TRUE
J 0
(1450 3400);
DISPLAY 0.872340 (1450 3400);
PAINT GREEN (1450 3400);
DISPLAY INVISIBLE (1450 3400);
FORCEADD RES..1
(-2750 3200);
FORCEPROP 1 LAST PART_NUMBER G21497-005
J 0
(-2725 3100);
DISPLAY 0.617021 (-2725 3100);
PAINT BLUE (-2725 3100);
FORCEPROP 1 LAST LOCATION R2T27
J 0
(-2800 3250);
DISPLAY 0.617021 (-2800 3250);
PAINT AQUA (-2800 3250);
FORCEPROP 1 LASTPIN (-2650 3200) $PN 2
J 0
(-2688 3212);
DISPLAY 0.617021 (-2688 3212);
PAINT ORANGE (-2688 3212);
FORCEPROP 1 LAST TOLERANCE 5%
J 0
(-2800 3150);
DISPLAY 0.617021 (-2800 3150);
PAINT SKYBLUE (-2800 3150);
FORCEPROP 1 LASTPIN (-2850 3200) $PN 1
J 0
(-2838 3212);
DISPLAY 0.617021 (-2838 3212);
PAINT ORANGE (-2838 3212);
FORCEPROP 1 LAST PACK_TYPE 0402
J 0
(-2825 3100);
DISPLAY 0.617021 (-2825 3100);
PAINT SKYBLUE (-2825 3100);
FORCEPROP 1 LAST VALUE 0.0
J 2
(-2850 3150);
DISPLAY 0.617021 (-2850 3150);
PAINT SKYBLUE (-2850 3150);
FORCEPROP 1 LAST MATERIAL CHIP
J 0
(-2950 3100);
DISPLAY 0.617021 (-2950 3100);
PAINT SKYBLUE (-2950 3100);
FORCEPROP 1 LAST WATTAGE 1/16W
J 2
(-2600 3150);
DISPLAY 0.617021 (-2600 3150);
PAINT SKYBLUE (-2600 3150);
FORCEPROP 1 LAST PATH I13
J 0
(-2800 3350);
DISPLAY 0.978723 (-2800 3350);
PAINT WHITE (-2800 3350);
DISPLAY INVISIBLE (-2800 3350);
FORCEPROP 2 LAST SEC 1
J 0
(-2800 3400);
DISPLAY 0.680851 (-2800 3400);
PAINT MONO (-2800 3400);
DISPLAY INVISIBLE (-2800 3400);
FORCEPROP 2 LAST SEC_TYPE 0402
J 0
(-2800 3400);
DISPLAY 1.021277 (-2800 3400);
PAINT ORANGE (-2800 3400);
DISPLAY INVISIBLE (-2800 3400);
FORCEPROP 2 LAST CDS_LIB mstr_discrete
J 0
(-2750 3200);
PAINT ORANGE (-2750 3200);
DISPLAY INVISIBLE (-2750 3200);
FORCEPROP 2 LAST BOM_COST PROC
J 2
(-2750 3200);
PAINT MONO (-2750 3200);
DISPLAY INVISIBLE (-2750 3200);
FORCEPROP 2 LAST CDS_LOCATION R2T27
J 0
(-2800 3250);
DISPLAY 0.617021 (-2800 3250);
PAINT AQUA (-2800 3250);
DISPLAY INVISIBLE (-2800 3250);
FORCEPROP 2 LAST ROOM PROC_SIDEBAND
J 0
(-2825 3125);
DISPLAY 0.617021 (-2825 3125);
PAINT ORANGE (-2825 3125);
DISPLAY INVISIBLE (-2825 3125);
FORCEADD OFFPAGE..5
(3225 650);
FORCEPROP 2 LAST $XR0 93 
J 0
(2971 650);
DISPLAY 0.638298 (2971 650);
PAINT MONO (2971 650);
FORCEPROP 1 LAST OFFPAGE TRUE
J 0
(3550 525);
DISPLAY 0.872340 (3550 525);
PAINT GREEN (3550 525);
DISPLAY INVISIBLE (3550 525);
FORCEPROP 2 LAST PATH I130
J 0
(3400 725);
DISPLAY 1.021277 (3400 725);
PAINT ORANGE (3400 725);
DISPLAY INVISIBLE (3400 725);
FORCEPROP 2 LAST CDS_LIB mstr_standard
J 0
(3225 650);
PAINT ORANGE (3225 650);
DISPLAY INVISIBLE (3225 650);
FORCEPROP 1 LAST COMMENT_BODY TRUE
J 0
(3325 575);
DISPLAY 0.872340 (3325 575);
PAINT GREEN (3325 575);
DISPLAY INVISIBLE (3325 575);
FORCEADD RES..1
(-2225 1250);
FORCEPROP 1 LAST PACK_TYPE 0402
J 0
(-2075 1200);
DISPLAY 0.617021 (-2075 1200);
PAINT SKYBLUE (-2075 1200);
FORCEPROP 1 LAST LOCATION R8F37
J 0
(-2275 1300);
DISPLAY 0.617021 (-2275 1300);
PAINT AQUA (-2275 1300);
FORCEPROP 1 LASTPIN (-2125 1250) $PN 2
J 0
(-2163 1262);
DISPLAY 0.617021 (-2163 1262);
PAINT ORANGE (-2163 1262);
FORCEPROP 1 LAST TOLERANCE 5%
J 0
(-2300 1200);
DISPLAY 0.617021 (-2300 1200);
PAINT SKYBLUE (-2300 1200);
FORCEPROP 1 LASTPIN (-2325 1250) $PN 1
J 0
(-2313 1262);
DISPLAY 0.617021 (-2313 1262);
PAINT ORANGE (-2313 1262);
FORCEPROP 1 LAST PART_NUMBER G21497-005
J 0
(-2375 1350);
DISPLAY 0.617021 (-2375 1350);
PAINT BLUE (-2375 1350);
FORCEPROP 1 LAST VALUE 0.0
J 2
(-2325 1250);
DISPLAY 0.617021 (-2325 1250);
PAINT SKYBLUE (-2325 1250);
FORCEPROP 1 LAST WATTAGE 1/16W
J 2
(-2325 1200);
DISPLAY 0.617021 (-2325 1200);
PAINT SKYBLUE (-2325 1200);
FORCEPROP 1 LAST MATERIAL EMPTY
J 0
(-2225 1200);
DISPLAY 0.617021 (-2225 1200);
PAINT RED (-2225 1200);
FORCEPROP 2 LAST SEC 1
J 0
(-2275 1450);
DISPLAY 0.680851 (-2275 1450);
PAINT MONO (-2275 1450);
DISPLAY INVISIBLE (-2275 1450);
FORCEPROP 2 LAST SEC_TYPE 0402
J 0
(-2275 1450);
DISPLAY 1.021277 (-2275 1450);
PAINT ORANGE (-2275 1450);
DISPLAY INVISIBLE (-2275 1450);
FORCEPROP 1 LAST PATH I131
J 0
(-2275 1400);
DISPLAY 0.978723 (-2275 1400);
PAINT WHITE (-2275 1400);
DISPLAY INVISIBLE (-2275 1400);
FORCEPROP 2 LAST CDS_LIB mstr_discrete
J 0
(-2225 1250);
PAINT ORANGE (-2225 1250);
DISPLAY INVISIBLE (-2225 1250);
FORCEADD OFFPAGE..2
(-1325 1250);
FORCEPROP 2 LAST $XR0 121 
J 0
(-1136 1250);
DISPLAY 0.638298 (-1136 1250);
PAINT MONO (-1136 1250);
FORCEPROP 1 LAST OFFPAGE TRUE
J 0
(-1000 1125);
DISPLAY 0.872340 (-1000 1125);
PAINT GREEN (-1000 1125);
DISPLAY INVISIBLE (-1000 1125);
FORCEPROP 2 LAST PATH I132
J 0
(-1150 1325);
DISPLAY 1.021277 (-1150 1325);
PAINT ORANGE (-1150 1325);
DISPLAY INVISIBLE (-1150 1325);
FORCEPROP 2 LAST CDS_LIB mstr_standard
J 0
(-1325 1250);
PAINT ORANGE (-1325 1250);
DISPLAY INVISIBLE (-1325 1250);
FORCEPROP 1 LAST COMMENT_BODY TRUE
J 0
(-1370 1155);
DISPLAY 0.872340 (-1370 1155);
PAINT GREEN (-1370 1155);
DISPLAY INVISIBLE (-1370 1155);
FORCEADD RES..1
(-2225 850);
FORCEPROP 1 LASTPIN (-2125 850) $PN 2
J 0
(-2163 862);
DISPLAY 0.617021 (-2163 862);
PAINT ORANGE (-2163 862);
FORCEPROP 1 LAST LOCATION R2T63
J 0
(-2275 900);
DISPLAY 0.617021 (-2275 900);
PAINT AQUA (-2275 900);
FORCEPROP 1 LAST MATERIAL EMPTY
J 0
(-2225 800);
DISPLAY 0.617021 (-2225 800);
PAINT RED (-2225 800);
FORCEPROP 1 LAST TOLERANCE 5%
J 0
(-2300 800);
DISPLAY 0.617021 (-2300 800);
PAINT SKYBLUE (-2300 800);
FORCEPROP 1 LASTPIN (-2325 850) $PN 1
J 0
(-2313 862);
DISPLAY 0.617021 (-2313 862);
PAINT ORANGE (-2313 862);
FORCEPROP 1 LAST PART_NUMBER G21497-005
J 0
(-2375 950);
DISPLAY 0.617021 (-2375 950);
PAINT BLUE (-2375 950);
FORCEPROP 1 LAST VALUE 0.0
J 2
(-2325 850);
DISPLAY 0.617021 (-2325 850);
PAINT SKYBLUE (-2325 850);
FORCEPROP 1 LAST WATTAGE 1/16W
J 2
(-2325 800);
DISPLAY 0.617021 (-2325 800);
PAINT SKYBLUE (-2325 800);
FORCEPROP 1 LAST PACK_TYPE 0402
J 0
(-2075 800);
DISPLAY 0.617021 (-2075 800);
PAINT SKYBLUE (-2075 800);
FORCEPROP 2 LAST SEC 1
J 0
(-2275 1050);
DISPLAY 0.680851 (-2275 1050);
PAINT MONO (-2275 1050);
DISPLAY INVISIBLE (-2275 1050);
FORCEPROP 2 LAST SEC_TYPE 0402
J 0
(-2275 1050);
DISPLAY 1.021277 (-2275 1050);
PAINT ORANGE (-2275 1050);
DISPLAY INVISIBLE (-2275 1050);
FORCEPROP 1 LAST PATH I133
J 0
(-2275 1000);
DISPLAY 0.978723 (-2275 1000);
PAINT WHITE (-2275 1000);
DISPLAY INVISIBLE (-2275 1000);
FORCEPROP 2 LAST CDS_LIB mstr_discrete
J 0
(-2225 850);
PAINT ORANGE (-2225 850);
DISPLAY INVISIBLE (-2225 850);
FORCEADD OFFPAGE..2
(-1325 850);
FORCEPROP 2 LAST $XR0 121 
J 0
(-1136 850);
DISPLAY 0.638298 (-1136 850);
PAINT MONO (-1136 850);
FORCEPROP 1 LAST OFFPAGE TRUE
J 0
(-1000 725);
DISPLAY 0.872340 (-1000 725);
PAINT GREEN (-1000 725);
DISPLAY INVISIBLE (-1000 725);
FORCEPROP 2 LAST PATH I134
J 0
(-1150 925);
DISPLAY 1.021277 (-1150 925);
PAINT ORANGE (-1150 925);
DISPLAY INVISIBLE (-1150 925);
FORCEPROP 2 LAST CDS_LIB mstr_standard
J 0
(-1325 850);
PAINT ORANGE (-1325 850);
DISPLAY INVISIBLE (-1325 850);
FORCEPROP 1 LAST COMMENT_BODY TRUE
J 0
(-1370 755);
DISPLAY 0.872340 (-1370 755);
PAINT GREEN (-1370 755);
DISPLAY INVISIBLE (-1370 755);
FORCEADD RES..1
(-2225 475);
FORCEPROP 1 LAST PACK_TYPE 0402
J 0
(-2075 425);
DISPLAY 0.617021 (-2075 425);
PAINT SKYBLUE (-2075 425);
FORCEPROP 1 LAST LOCATION R1T35
J 0
(-2275 525);
DISPLAY 0.617021 (-2275 525);
PAINT AQUA (-2275 525);
FORCEPROP 1 LAST PART_NUMBER G21497-005
J 0
(-2375 575);
DISPLAY 0.617021 (-2375 575);
PAINT BLUE (-2375 575);
FORCEPROP 1 LASTPIN (-2325 475) $PN 1
J 0
(-2313 487);
DISPLAY 0.617021 (-2313 487);
PAINT ORANGE (-2313 487);
FORCEPROP 1 LASTPIN (-2125 475) $PN 2
J 0
(-2163 487);
DISPLAY 0.617021 (-2163 487);
PAINT ORANGE (-2163 487);
FORCEPROP 1 LAST MATERIAL EMPTY
J 0
(-2225 425);
DISPLAY 0.617021 (-2225 425);
PAINT RED (-2225 425);
FORCEPROP 1 LAST TOLERANCE 5%
J 0
(-2300 425);
DISPLAY 0.617021 (-2300 425);
PAINT SKYBLUE (-2300 425);
FORCEPROP 1 LAST VALUE 0.0
J 2
(-2325 475);
DISPLAY 0.617021 (-2325 475);
PAINT SKYBLUE (-2325 475);
FORCEPROP 1 LAST WATTAGE 1/16W
J 2
(-2325 425);
DISPLAY 0.617021 (-2325 425);
PAINT SKYBLUE (-2325 425);
FORCEPROP 2 LAST SEC 1
J 0
(-2275 675);
DISPLAY 0.680851 (-2275 675);
PAINT MONO (-2275 675);
DISPLAY INVISIBLE (-2275 675);
FORCEPROP 2 LAST SEC_TYPE 0402
J 0
(-2275 675);
DISPLAY 1.021277 (-2275 675);
PAINT ORANGE (-2275 675);
DISPLAY INVISIBLE (-2275 675);
FORCEPROP 1 LAST PATH I135
J 0
(-2275 625);
DISPLAY 0.978723 (-2275 625);
PAINT WHITE (-2275 625);
DISPLAY INVISIBLE (-2275 625);
FORCEPROP 2 LAST CDS_LIB mstr_discrete
J 0
(-2225 475);
PAINT ORANGE (-2225 475);
DISPLAY INVISIBLE (-2225 475);
FORCEADD OFFPAGE..2
(-1325 475);
FORCEPROP 2 LAST $XR0 121 
J 0
(-1136 475);
DISPLAY 0.638298 (-1136 475);
PAINT MONO (-1136 475);
FORCEPROP 1 LAST OFFPAGE TRUE
J 0
(-1000 350);
DISPLAY 0.872340 (-1000 350);
PAINT GREEN (-1000 350);
DISPLAY INVISIBLE (-1000 350);
FORCEPROP 2 LAST PATH I136
J 0
(-1150 550);
DISPLAY 1.021277 (-1150 550);
PAINT ORANGE (-1150 550);
DISPLAY INVISIBLE (-1150 550);
FORCEPROP 2 LAST CDS_LIB mstr_standard
J 0
(-1325 475);
PAINT ORANGE (-1325 475);
DISPLAY INVISIBLE (-1325 475);
FORCEPROP 1 LAST COMMENT_BODY TRUE
J 0
(-1370 380);
DISPLAY 0.872340 (-1370 380);
PAINT GREEN (-1370 380);
DISPLAY INVISIBLE (-1370 380);
FORCEADD RES..1
(-2225 75);
FORCEPROP 1 LAST PACK_TYPE 0402
J 0
(-2125 25);
DISPLAY 0.617021 (-2125 25);
PAINT SKYBLUE (-2125 25);
FORCEPROP 1 LASTPIN (-2125 75) $PN 2
J 0
(-2163 87);
DISPLAY 0.617021 (-2163 87);
PAINT ORANGE (-2163 87);
FORCEPROP 1 LAST LOCATION R1T38
J 0
(-2275 125);
DISPLAY 0.617021 (-2275 125);
PAINT AQUA (-2275 125);
FORCEPROP 1 LAST MATERIAL EMPTY
J 0
(-2225 25);
DISPLAY 0.617021 (-2225 25);
PAINT RED (-2225 25);
FORCEPROP 1 LAST TOLERANCE 5%
J 0
(-2300 25);
DISPLAY 0.617021 (-2300 25);
PAINT SKYBLUE (-2300 25);
FORCEPROP 1 LASTPIN (-2325 75) $PN 1
J 0
(-2313 87);
DISPLAY 0.617021 (-2313 87);
PAINT ORANGE (-2313 87);
FORCEPROP 1 LAST PART_NUMBER G21497-005
J 0
(-2375 175);
DISPLAY 0.617021 (-2375 175);
PAINT BLUE (-2375 175);
FORCEPROP 1 LAST VALUE 0.0
J 2
(-2325 75);
DISPLAY 0.617021 (-2325 75);
PAINT SKYBLUE (-2325 75);
FORCEPROP 1 LAST WATTAGE 1/16W
J 2
(-2325 25);
DISPLAY 0.617021 (-2325 25);
PAINT SKYBLUE (-2325 25);
FORCEPROP 2 LAST SEC 1
J 0
(-2275 275);
DISPLAY 0.680851 (-2275 275);
PAINT MONO (-2275 275);
DISPLAY INVISIBLE (-2275 275);
FORCEPROP 2 LAST SEC_TYPE 0402
J 0
(-2275 275);
DISPLAY 1.021277 (-2275 275);
PAINT ORANGE (-2275 275);
DISPLAY INVISIBLE (-2275 275);
FORCEPROP 1 LAST PATH I137
J 0
(-2275 225);
DISPLAY 0.978723 (-2275 225);
PAINT WHITE (-2275 225);
DISPLAY INVISIBLE (-2275 225);
FORCEPROP 2 LAST CDS_LIB mstr_discrete
J 0
(-2225 75);
PAINT ORANGE (-2225 75);
DISPLAY INVISIBLE (-2225 75);
FORCEADD OFFPAGE..2
(-1325 75);
FORCEPROP 2 LAST $XR0 121 
J 0
(-1136 75);
DISPLAY 0.638298 (-1136 75);
PAINT MONO (-1136 75);
FORCEPROP 2 LAST PATH I138
J 0
(-1150 150);
DISPLAY 1.021277 (-1150 150);
PAINT ORANGE (-1150 150);
DISPLAY INVISIBLE (-1150 150);
FORCEPROP 2 LAST CDS_LIB mstr_standard
J 0
(-1325 75);
PAINT ORANGE (-1325 75);
DISPLAY INVISIBLE (-1325 75);
FORCEPROP 1 LAST COMMENT_BODY TRUE
J 0
(-1370 -20);
DISPLAY 0.872340 (-1370 -20);
PAINT GREEN (-1370 -20);
DISPLAY INVISIBLE (-1370 -20);
FORCEPROP 1 LAST OFFPAGE TRUE
J 0
(-1000 -50);
DISPLAY 0.872340 (-1000 -50);
PAINT GREEN (-1000 -50);
DISPLAY INVISIBLE (-1000 -50);
FORCEADD RES..2
(-2475 2525);
FORCEPROP 1 LAST LOCATION R2T72
J 0
(-2430 2650);
DISPLAY 0.617021 (-2430 2650);
PAINT AQUA (-2430 2650);
FORCEPROP 1 LAST VALUE 150.0
J 0
(-2430 2600);
DISPLAY 0.617021 (-2430 2600);
PAINT SKYBLUE (-2430 2600);
FORCEPROP 1 LASTPIN (-2475 2625) $PN 1
J 0
(-2470 2587);
DISPLAY 0.617021 (-2470 2587);
PAINT ORANGE (-2470 2587);
FORCEPROP 1 LAST TOLERANCE 1%
J 0
(-2430 2550);
DISPLAY 0.617021 (-2430 2550);
PAINT SKYBLUE (-2430 2550);
FORCEPROP 1 LAST PART_NUMBER G21796-009
J 0
(-2435 2400);
DISPLAY 0.617021 (-2435 2400);
PAINT BLUE (-2435 2400);
FORCEPROP 1 LAST WATTAGE 1/16W
J 0
(-2435 2500);
DISPLAY 0.617021 (-2435 2500);
PAINT SKYBLUE (-2435 2500);
FORCEPROP 1 LAST MATERIAL CHIP
J 0
(-2435 2450);
DISPLAY 0.617021 (-2435 2450);
PAINT SKYBLUE (-2435 2450);
FORCEPROP 1 LAST PACK_TYPE 0402
J 0
(-2435 2350);
DISPLAY 0.617021 (-2435 2350);
PAINT SKYBLUE (-2435 2350);
FORCEPROP 1 LASTPIN (-2475 2425) $PN 2
J 0
(-2470 2435);
DISPLAY 0.617021 (-2470 2435);
PAINT ORANGE (-2470 2435);
FORCEPROP 2 LAST CDS_LOCATION R2T72
J 0
(-2430 2650);
DISPLAY 0.617021 (-2430 2650);
PAINT AQUA (-2430 2650);
DISPLAY INVISIBLE (-2430 2650);
FORCEPROP 1 LAST PATH I143
J 0
(-2425 2700);
DISPLAY 0.978723 (-2425 2700);
PAINT WHITE (-2425 2700);
DISPLAY INVISIBLE (-2425 2700);
FORCEPROP 0 LAST CDS_SEC 1
J 0
(-2425 2700);
PAINT ORANGE (-2425 2700);
DISPLAY INVISIBLE (-2425 2700);
FORCEPROP 2 LAST SEC_TYPE 0402
J 0
(-2425 2750);
DISPLAY 1.021277 (-2425 2750);
PAINT ORANGE (-2425 2750);
DISPLAY INVISIBLE (-2425 2750);
FORCEPROP 2 LAST SEC 1
J 0
(-2425 2750);
DISPLAY 0.680851 (-2425 2750);
PAINT MONO (-2425 2750);
DISPLAY INVISIBLE (-2425 2750);
FORCEPROP 2 LAST CDS_LIB mstr_discrete
J 0
(-2475 2525);
PAINT MONO (-2475 2525);
DISPLAY INVISIBLE (-2475 2525);
FORCEPROP 2 LAST BOM_COST PROC_SIDEBAND
J 0
(-2475 2525);
PAINT MONO (-2475 2525);
DISPLAY INVISIBLE (-2475 2525);
FORCEPROP 2 LAST ROOM PROC_SIDEBAND
J 0
(-2450 2300);
PAINT ORANGE (-2450 2300);
DISPLAY INVISIBLE (-2450 2300);
FORCEADD RES..2
(-1900 2500);
FORCEPROP 1 LAST PART_NUMBER G21796-009
J 0
(-1860 2375);
DISPLAY 0.617021 (-1860 2375);
PAINT BLUE (-1860 2375);
FORCEPROP 1 LAST WATTAGE 1/16W
J 0
(-1860 2475);
DISPLAY 0.617021 (-1860 2475);
PAINT SKYBLUE (-1860 2475);
FORCEPROP 1 LAST LOCATION R2T73
J 0
(-1855 2625);
DISPLAY 0.617021 (-1855 2625);
PAINT AQUA (-1855 2625);
FORCEPROP 1 LAST TOLERANCE 1%
J 0
(-1855 2525);
DISPLAY 0.617021 (-1855 2525);
PAINT SKYBLUE (-1855 2525);
FORCEPROP 1 LAST MATERIAL CHIP
J 0
(-1860 2425);
DISPLAY 0.617021 (-1860 2425);
PAINT SKYBLUE (-1860 2425);
FORCEPROP 1 LAST PACK_TYPE 0402
J 0
(-1860 2325);
DISPLAY 0.617021 (-1860 2325);
PAINT SKYBLUE (-1860 2325);
FORCEPROP 1 LASTPIN (-1900 2400) $PN 2
J 0
(-1895 2410);
DISPLAY 0.617021 (-1895 2410);
PAINT ORANGE (-1895 2410);
FORCEPROP 1 LAST VALUE 150.0
J 0
(-1855 2575);
DISPLAY 0.617021 (-1855 2575);
PAINT SKYBLUE (-1855 2575);
FORCEPROP 1 LASTPIN (-1900 2600) $PN 1
J 0
(-1895 2562);
DISPLAY 0.617021 (-1895 2562);
PAINT ORANGE (-1895 2562);
FORCEPROP 2 LAST CDS_LOCATION R2T73
J 0
(-1855 2625);
DISPLAY 0.617021 (-1855 2625);
PAINT AQUA (-1855 2625);
DISPLAY INVISIBLE (-1855 2625);
FORCEPROP 0 LAST CDS_SEC 1
J 0
(-1850 2675);
PAINT ORANGE (-1850 2675);
DISPLAY INVISIBLE (-1850 2675);
FORCEPROP 2 LAST SEC 1
J 0
(-1850 2725);
DISPLAY 0.680851 (-1850 2725);
PAINT MONO (-1850 2725);
DISPLAY INVISIBLE (-1850 2725);
FORCEPROP 1 LAST PATH I144
J 0
(-1850 2675);
DISPLAY 0.978723 (-1850 2675);
PAINT WHITE (-1850 2675);
DISPLAY INVISIBLE (-1850 2675);
FORCEPROP 2 LAST SEC_TYPE 0402
J 0
(-1850 2725);
DISPLAY 1.021277 (-1850 2725);
PAINT ORANGE (-1850 2725);
DISPLAY INVISIBLE (-1850 2725);
FORCEPROP 2 LAST BOM_COST PROC_SIDEBAND
J 0
(-1900 2500);
PAINT MONO (-1900 2500);
DISPLAY INVISIBLE (-1900 2500);
FORCEPROP 2 LAST CDS_LIB mstr_discrete
J 0
(-1900 2500);
PAINT MONO (-1900 2500);
DISPLAY INVISIBLE (-1900 2500);
FORCEPROP 2 LAST ROOM PROC_SIDEBAND
J 0
(-1875 2275);
PAINT ORANGE (-1875 2275);
DISPLAY INVISIBLE (-1875 2275);
FORCEADD P3V3..1
(2300 1300);
FORCEPROP 3 LASTPIN (2300 1250) SIG_NAME P3V3\g
J 0
(2310 1260);
DISPLAY 0.659574 (2310 1260);
PAINT MONO (2310 1260);
DISPLAY INVISIBLE (2310 1260);
FORCEPROP 1 LAST SIZE 1B
J 0
(2345 1322);
DISPLAY 0.340426 (2345 1322);
PAINT GREEN (2345 1322);
DISPLAY INVISIBLE (2345 1322);
FORCEPROP 1 LAST BODY_TYPE PLUMBING
J 0
(2255 1257);
DISPLAY 0.340426 (2255 1257);
PAINT GREEN (2255 1257);
DISPLAY INVISIBLE (2255 1257);
FORCEPROP 1 LAST VOLTAGE 3.3V
J 0
(2255 1257);
DISPLAY 0.340426 (2255 1257);
PAINT SKYBLUE (2255 1257);
DISPLAY INVISIBLE (2255 1257);
FORCEPROP 2 LAST CDS_LIB mstr_symbols
J 0
(2300 1300);
PAINT ORANGE (2300 1300);
DISPLAY INVISIBLE (2300 1300);
FORCEPROP 1 LAST HDL_POWER P3V3
J 0
(1975 1175);
DISPLAY 0.872340 (1975 1175);
PAINT ORANGE (1975 1175);
DISPLAY INVISIBLE (1975 1175);
FORCEPROP 1 LAST PATH I145
J 0
(2345 1302);
DISPLAY 0.340426 (2345 1302);
PAINT GREEN (2345 1302);
DISPLAY INVISIBLE (2345 1302);
FORCEADD PVCCIO_CPU0..1
(1750 1300);
FORCEPROP 3 LASTPIN (1750 1250) SIG_NAME PVCCIO_CPU0\g
J 0
(1760 1260);
DISPLAY 0.659574 (1760 1260);
PAINT MONO (1760 1260);
DISPLAY INVISIBLE (1760 1260);
FORCEPROP 1 LAST PATH I146
J 0
(1800 1325);
DISPLAY 0.872340 (1800 1325);
PAINT AQUA (1800 1325);
DISPLAY INVISIBLE (1800 1325);
FORCEPROP 1 LAST HDL_POWER PVCCIO_CPU0
J 1
(1750 1350);
DISPLAY 0.872340 (1750 1350);
PAINT GREEN (1750 1350);
DISPLAY INVISIBLE (1750 1350);
FORCEPROP 1 LAST BODY_TYPE PLUMBING
J 0
(1705 1257);
DISPLAY 0.340426 (1705 1257);
PAINT GREEN (1705 1257);
DISPLAY INVISIBLE (1705 1257);
FORCEPROP 1 LAST VOLTAGE 1.1V
J 0
(1705 1257);
DISPLAY 0.340426 (1705 1257);
PAINT SKYBLUE (1705 1257);
DISPLAY INVISIBLE (1705 1257);
FORCEPROP 2 LAST CDS_LIB mstr_symbols
J 0
(1750 1300);
PAINT ORANGE (1750 1300);
DISPLAY INVISIBLE (1750 1300);
FORCEADD RES..2
(1750 1100);
FORCEPROP 1 LAST LOCATION R2W2
J 0
(1870 1225);
DISPLAY 0.617021 (1870 1225);
PAINT AQUA (1870 1225);
FORCEPROP 1 LAST WATTAGE 1/16W
J 0
(1865 1075);
DISPLAY 0.617021 (1865 1075);
PAINT SKYBLUE (1865 1075);
FORCEPROP 1 LAST TOLERANCE 1%
J 0
(1870 1125);
DISPLAY 0.617021 (1870 1125);
PAINT SKYBLUE (1870 1125);
FORCEPROP 1 LAST PART_NUMBER G21796-047
J 0
(1865 975);
DISPLAY 0.617021 (1865 975);
PAINT BLUE (1865 975);
FORCEPROP 1 LAST MATERIAL EMPTY
J 0
(1865 1025);
DISPLAY 0.617021 (1865 1025);
PAINT RED (1865 1025);
FORCEPROP 1 LAST VALUE 49.9
J 0
(1870 1175);
DISPLAY 0.617021 (1870 1175);
PAINT SKYBLUE (1870 1175);
FORCEPROP 1 LAST PACK_TYPE 0402
J 0
(1865 925);
DISPLAY 0.617021 (1865 925);
PAINT SKYBLUE (1865 925);
FORCEPROP 1 LASTPIN (1750 1200) $PN 1
J 0
(1755 1162);
DISPLAY 0.617021 (1755 1162);
PAINT ORANGE (1755 1162);
FORCEPROP 1 LASTPIN (1750 1000) $PN 2
J 0
(1755 1010);
DISPLAY 0.617021 (1755 1010);
PAINT ORANGE (1755 1010);
FORCEPROP 1 LAST PATH I147
J 0
(1800 1275);
DISPLAY 0.978723 (1800 1275);
PAINT WHITE (1800 1275);
DISPLAY INVISIBLE (1800 1275);
FORCEPROP 0 LAST CDS_SEC 1
J 0
(1800 1275);
DISPLAY INVISIBLE (1800 1275);
FORCEPROP 2 LAST SEC_TYPE 0402
J 0
(1800 1325);
DISPLAY 1.021277 (1800 1325);
PAINT ORANGE (1800 1325);
DISPLAY INVISIBLE (1800 1325);
FORCEPROP 2 LAST SEC 1
J 0
(1800 1325);
DISPLAY 0.680851 (1800 1325);
PAINT MONO (1800 1325);
DISPLAY INVISIBLE (1800 1325);
FORCEPROP 0 LAST ROOM SB
J 0
(1700 1300);
DISPLAY 1.021277 (1700 1300);
PAINT ORANGE (1700 1300);
DISPLAY INVISIBLE (1700 1300);
FORCEPROP 2 LAST CDS_LIB mstr_discrete
J 0
(1750 1100);
PAINT ORANGE (1750 1100);
DISPLAY INVISIBLE (1750 1100);
FORCEPROP 2 LAST CDS_LOCATION R2W2
J 0
(1795 1225);
DISPLAY 0.617021 (1795 1225);
PAINT AQUA (1795 1225);
DISPLAY INVISIBLE (1795 1225);
FORCEADD 374R2F-1-GP..1
(2300 1075);
FORCEPROP 2 LAST ATTRIBUTE 374 OHM
J 0
(2350 1100);
DISPLAY 0.638298 (2350 1100);
PAINT GREEN (2350 1100);
FORCEPROP 2 LAST TOLERANCE 1%
J 0
(2350 1050);
DISPLAY 0.638298 (2350 1050);
PAINT GREEN (2350 1050);
FORCEPROP 2 LAST RATED 1/16W
J 0
(2350 1000);
DISPLAY 0.638298 (2350 1000);
PAINT GREEN (2350 1000);
FORCEPROP 1 LAST LOCATION R2T36
J 0
(2350 1205);
DISPLAY 0.617021 (2350 1205);
PAINT GREEN (2350 1205);
FORCEPROP 2 LAST PACK_SIZE 0402
J 0
(2350 950);
DISPLAY 0.638298 (2350 950);
PAINT GREEN (2350 950);
FORCEPROP 1 LAST VALUE 374R2F-1-GP
J 0
(2350 1150);
DISPLAY 0.617021 (2350 1150);
PAINT GREEN (2350 1150);
FORCEPROP 1 LAST PATH I148
J 0
(2300 1075);
DISPLAY 0.617021 (2300 1075);
PAINT GREEN (2300 1075);
DISPLAY INVISIBLE (2300 1075);
FORCEPROP 1 LAST CDS_LMAN_SYM_OUTLINE -50,75,50,-75
J 0
(2300 1075);
DISPLAY 0.468085 (2300 1075);
PAINT GREEN (2300 1075);
DISPLAY INVISIBLE (2300 1075);
FORCEPROP 2 LAST CDS_LIB w_hdl
J 0
(2300 1075);
DISPLAY INVISIBLE (2300 1075);
FORCEPROP 1 LAST PART_NUMBER 64.37405.6DL
J 0
(2300 1075);
DISPLAY 0.617021 (2300 1075);
PAINT GREEN (2300 1075);
DISPLAY INVISIBLE (2300 1075);
FORCEPROP 1 LAST PACK_TYPE SMD-RG
J 0
(2300 1075);
DISPLAY 0.617021 (2300 1075);
PAINT GREEN (2300 1075);
DISPLAY INVISIBLE (2300 1075);
FORCEADD RES..1
(-2750 3425);
FORCEPROP 1 LAST PART_NUMBER G21497-005
J 0
(-2725 3325);
DISPLAY 0.617021 (-2725 3325);
PAINT BLUE (-2725 3325);
FORCEPROP 1 LAST LOCATION R2T32
J 0
(-2800 3475);
DISPLAY 0.617021 (-2800 3475);
PAINT AQUA (-2800 3475);
FORCEPROP 1 LAST WATTAGE 1/16W
J 2
(-2600 3375);
DISPLAY 0.617021 (-2600 3375);
PAINT SKYBLUE (-2600 3375);
FORCEPROP 1 LASTPIN (-2650 3425) $PN 2
J 0
(-2688 3437);
DISPLAY 0.617021 (-2688 3437);
PAINT ORANGE (-2688 3437);
FORCEPROP 1 LAST TOLERANCE 5%
J 0
(-2800 3375);
DISPLAY 0.617021 (-2800 3375);
PAINT SKYBLUE (-2800 3375);
FORCEPROP 1 LASTPIN (-2850 3425) $PN 1
J 0
(-2838 3437);
DISPLAY 0.617021 (-2838 3437);
PAINT ORANGE (-2838 3437);
FORCEPROP 1 LAST MATERIAL CHIP
J 0
(-2950 3325);
DISPLAY 0.617021 (-2950 3325);
PAINT SKYBLUE (-2950 3325);
FORCEPROP 1 LAST VALUE 0.0
J 2
(-2850 3375);
DISPLAY 0.617021 (-2850 3375);
PAINT SKYBLUE (-2850 3375);
FORCEPROP 1 LAST PACK_TYPE 0402
J 0
(-2825 3325);
DISPLAY 0.617021 (-2825 3325);
PAINT SKYBLUE (-2825 3325);
FORCEPROP 2 LAST SEC_TYPE 0402
J 0
(-2800 3625);
DISPLAY 1.021277 (-2800 3625);
PAINT ORANGE (-2800 3625);
DISPLAY INVISIBLE (-2800 3625);
FORCEPROP 2 LAST SEC 1
J 0
(-2800 3625);
DISPLAY 0.680851 (-2800 3625);
PAINT MONO (-2800 3625);
DISPLAY INVISIBLE (-2800 3625);
FORCEPROP 1 LAST PATH I15
J 0
(-2800 3575);
DISPLAY 0.978723 (-2800 3575);
PAINT WHITE (-2800 3575);
DISPLAY INVISIBLE (-2800 3575);
FORCEPROP 2 LAST CDS_LIB mstr_discrete
J 0
(-2750 3425);
PAINT ORANGE (-2750 3425);
DISPLAY INVISIBLE (-2750 3425);
FORCEPROP 2 LAST BOM_COST PROC
J 2
(-2750 3425);
PAINT MONO (-2750 3425);
DISPLAY INVISIBLE (-2750 3425);
FORCEPROP 2 LAST CDS_LOCATION R2T32
J 0
(-2800 3475);
DISPLAY 0.617021 (-2800 3475);
PAINT AQUA (-2800 3475);
DISPLAY INVISIBLE (-2800 3475);
FORCEPROP 2 LAST ROOM PROC_SIDEBAND
J 0
(-2825 3350);
DISPLAY 0.617021 (-2825 3350);
PAINT ORANGE (-2825 3350);
DISPLAY INVISIBLE (-2825 3350);
FORCEADD RES..1
(-2750 3725);
FORCEPROP 1 LASTPIN (-2650 3725) $PN 2
J 0
(-2688 3737);
DISPLAY 0.617021 (-2688 3737);
PAINT MONO (-2688 3737);
FORCEPROP 1 LAST MATERIAL CHIP
J 0
(-2950 3625);
DISPLAY 0.617021 (-2950 3625);
PAINT SKYBLUE (-2950 3625);
FORCEPROP 1 LAST VALUE 0.0
J 2
(-2850 3675);
DISPLAY 0.617021 (-2850 3675);
PAINT SKYBLUE (-2850 3675);
FORCEPROP 1 LAST TOLERANCE 5%
J 0
(-2800 3675);
DISPLAY 0.617021 (-2800 3675);
PAINT SKYBLUE (-2800 3675);
FORCEPROP 1 LASTPIN (-2850 3725) $PN 1
J 0
(-2838 3737);
DISPLAY 0.617021 (-2838 3737);
PAINT MONO (-2838 3737);
FORCEPROP 1 LAST LOCATION R2T20
J 0
(-2825 3800);
DISPLAY 0.617021 (-2825 3800);
PAINT AQUA (-2825 3800);
FORCEPROP 1 LAST WATTAGE 1/16W
J 2
(-2600 3675);
DISPLAY 0.617021 (-2600 3675);
PAINT SKYBLUE (-2600 3675);
FORCEPROP 1 LAST PACK_TYPE 0402
J 0
(-2825 3625);
DISPLAY 0.617021 (-2825 3625);
PAINT SKYBLUE (-2825 3625);
FORCEPROP 1 LAST PART_NUMBER G21497-005
J 0
(-2725 3625);
DISPLAY 0.617021 (-2725 3625);
PAINT BLUE (-2725 3625);
FORCEPROP 1 LAST PATH I16
J 0
(-2800 3875);
DISPLAY 0.978723 (-2800 3875);
PAINT WHITE (-2800 3875);
DISPLAY INVISIBLE (-2800 3875);
FORCEPROP 2 LAST SEC_TYPE 0402
J 0
(-2800 3925);
DISPLAY 1.021277 (-2800 3925);
PAINT ORANGE (-2800 3925);
DISPLAY INVISIBLE (-2800 3925);
FORCEPROP 2 LAST SEC 1
J 0
(-2800 3925);
DISPLAY 0.680851 (-2800 3925);
PAINT MONO (-2800 3925);
DISPLAY INVISIBLE (-2800 3925);
FORCEPROP 2 LAST BOM_COST PROC
J 0
(-2750 3725);
PAINT MONO (-2750 3725);
DISPLAY INVISIBLE (-2750 3725);
FORCEPROP 2 LAST CDS_LIB mstr_discrete
J 0
(-2750 3725);
PAINT ORANGE (-2750 3725);
DISPLAY INVISIBLE (-2750 3725);
FORCEPROP 2 LAST ROOM PROC_SIDEBAND
J 0
(-2825 3650);
DISPLAY 0.617021 (-2825 3650);
PAINT ORANGE (-2825 3650);
DISPLAY INVISIBLE (-2825 3650);
FORCEPROP 2 LAST CDS_LOCATION R2T20
J 0
(-2825 3800);
DISPLAY 0.617021 (-2825 3800);
PAINT AQUA (-2825 3800);
DISPLAY INVISIBLE (-2825 3800);
FORCEADD OFFPAGE..1
(-3400 3975);
FORCEPROP 2 LAST $XR0 21 
J 0
(-3621 3975);
DISPLAY 0.638298 (-3621 3975);
PAINT MONO (-3621 3975);
FORCEPROP 1 LAST OFFPAGE TRUE
J 0
(-3075 3850);
PAINT GREEN (-3075 3850);
DISPLAY INVISIBLE (-3075 3850);
FORCEPROP 1 LAST COMMENT_BODY TRUE
J 0
(-3275 3875);
DISPLAY 1.170213 (-3275 3875);
PAINT GREEN (-3275 3875);
DISPLAY INVISIBLE (-3275 3875);
FORCEPROP 2 LAST CDS_LIB mstr_standard
J 0
(-3400 3975);
PAINT ORANGE (-3400 3975);
DISPLAY INVISIBLE (-3400 3975);
FORCEPROP 2 LAST PATH I19
J 0
(-3600 4025);
DISPLAY 1.021277 (-3600 4025);
PAINT ORANGE (-3600 4025);
DISPLAY INVISIBLE (-3600 4025);
FORCEADD RES..1
(-2750 3975);
FORCEPROP 1 LAST PACK_TYPE 0402
J 0
(-2825 3875);
DISPLAY 0.617021 (-2825 3875);
PAINT SKYBLUE (-2825 3875);
FORCEPROP 1 LAST WATTAGE 1/16W
J 2
(-2600 3925);
DISPLAY 0.617021 (-2600 3925);
PAINT SKYBLUE (-2600 3925);
FORCEPROP 1 LASTPIN (-2650 3975) $PN 2
J 0
(-2688 3987);
DISPLAY 0.617021 (-2688 3987);
PAINT MONO (-2688 3987);
FORCEPROP 1 LASTPIN (-2850 3975) $PN 1
J 0
(-2838 3987);
DISPLAY 0.617021 (-2838 3987);
PAINT MONO (-2838 3987);
FORCEPROP 1 LAST LOCATION R2T17
J 0
(-2825 4050);
DISPLAY 0.617021 (-2825 4050);
PAINT AQUA (-2825 4050);
FORCEPROP 1 LAST MATERIAL CHIP
J 0
(-2950 3875);
DISPLAY 0.617021 (-2950 3875);
PAINT SKYBLUE (-2950 3875);
FORCEPROP 1 LAST VALUE 0.0
J 2
(-2850 3925);
DISPLAY 0.617021 (-2850 3925);
PAINT SKYBLUE (-2850 3925);
FORCEPROP 1 LAST TOLERANCE 5%
J 0
(-2800 3925);
DISPLAY 0.617021 (-2800 3925);
PAINT SKYBLUE (-2800 3925);
FORCEPROP 1 LAST PART_NUMBER G21497-005
J 0
(-2725 3875);
DISPLAY 0.617021 (-2725 3875);
PAINT BLUE (-2725 3875);
FORCEPROP 2 LAST SEC_TYPE 0402
J 0
(-2800 4175);
DISPLAY 1.021277 (-2800 4175);
PAINT ORANGE (-2800 4175);
DISPLAY INVISIBLE (-2800 4175);
FORCEPROP 2 LAST SEC 1
J 0
(-2800 4175);
DISPLAY 0.680851 (-2800 4175);
PAINT MONO (-2800 4175);
DISPLAY INVISIBLE (-2800 4175);
FORCEPROP 1 LAST PATH I23
J 0
(-2800 4125);
DISPLAY 0.978723 (-2800 4125);
PAINT WHITE (-2800 4125);
DISPLAY INVISIBLE (-2800 4125);
FORCEPROP 2 LAST CDS_LIB mstr_discrete
J 0
(-2750 3975);
PAINT ORANGE (-2750 3975);
DISPLAY INVISIBLE (-2750 3975);
FORCEPROP 2 LAST BOM_COST PROC
J 2
(-2750 3975);
PAINT MONO (-2750 3975);
DISPLAY INVISIBLE (-2750 3975);
FORCEPROP 2 LAST ROOM PROC_SIDEBAND
J 0
(-2825 3900);
DISPLAY 0.617021 (-2825 3900);
PAINT ORANGE (-2825 3900);
DISPLAY INVISIBLE (-2825 3900);
FORCEPROP 2 LAST CDS_LOCATION R2T17
J 0
(-2825 4050);
DISPLAY 0.617021 (-2825 4050);
PAINT AQUA (-2825 4050);
DISPLAY INVISIBLE (-2825 4050);
FORCEADD GND..1
(-200 2825);
FORCEPROP 3 LASTPIN (-200 2875) SIG_NAME GND\g
J 0
(-190 2885);
DISPLAY 0.659574 (-190 2885);
PAINT MONO (-190 2885);
DISPLAY INVISIBLE (-190 2885);
FORCEPROP 1 LAST PATH I29
J 0
(-125 2825);
DISPLAY 0.872340 (-125 2825);
PAINT AQUA (-125 2825);
DISPLAY INVISIBLE (-125 2825);
FORCEPROP 1 LAST HDL_POWER GND
J 0
(-200 2975);
DISPLAY 1.212766 (-200 2975);
PAINT GREEN (-200 2975);
DISPLAY INVISIBLE (-200 2975);
FORCEPROP 1 LAST VOLTAGE 0
J 0
(-200 2825);
PAINT SKYBLUE (-200 2825);
DISPLAY INVISIBLE (-200 2825);
FORCEPROP 2 LAST CDS_LIB mstr_symbols
J 0
(-200 2825);
PAINT MONO (-200 2825);
DISPLAY INVISIBLE (-200 2825);
FORCEPROP 1 LAST SIZE 1B
J 0
(-125 2775);
DISPLAY 1.212766 (-125 2775);
PAINT GREEN (-125 2775);
DISPLAY INVISIBLE (-125 2775);
FORCEPROP 1 LAST BODY_TYPE PLUMBING
J 0
(-245 2782);
DISPLAY 0.340426 (-245 2782);
PAINT GREEN (-245 2782);
DISPLAY INVISIBLE (-245 2782);
FORCEADD GTL2014..1
R 2
(425 3350);
FORCEPROP 2 LASTPIN (875 3650) $PN 14
J 0
(885 3660);
DISPLAY 0.617021 (885 3660);
PAINT ORANGE (885 3660);
FORCEPROP 2 LASTPIN (875 3600) $PN 4
J 0
(885 3610);
DISPLAY 0.617021 (885 3610);
PAINT ORANGE (885 3610);
FORCEPROP 1 LAST LOCATION U2T4
J 2
(825 3900);
DISPLAY 0.617021 (825 3900);
PAINT AQUA (825 3900);
FORCEPROP 1 LAST MATERIAL IC
J 2
(825 3850);
DISPLAY 0.617021 (825 3850);
PAINT SKYBLUE (825 3850);
FORCEPROP 2 LASTPIN (875 3500) $PN 1
J 0
(885 3510);
DISPLAY 0.617021 (885 3510);
PAINT ORANGE (885 3510);
FORCEPROP 2 LASTPIN (875 3350) $PN 9
J 0
(885 3360);
DISPLAY 0.617021 (885 3360);
PAINT ORANGE (885 3360);
FORCEPROP 2 LASTPIN (875 3300) $PN 10
J 0
(885 3310);
DISPLAY 0.617021 (885 3310);
PAINT ORANGE (885 3310);
FORCEPROP 2 LASTPIN (875 3250) $PN 12
J 0
(885 3260);
DISPLAY 0.617021 (885 3260);
PAINT ORANGE (885 3260);
FORCEPROP 2 LASTPIN (875 3200) $PN 13
J 0
(885 3210);
DISPLAY 0.617021 (885 3210);
PAINT ORANGE (885 3210);
FORCEPROP 1 LAST PART_NUMBER D66151-001
J 2
(825 2825);
DISPLAY 0.617021 (825 2825);
PAINT BLUE (825 2825);
FORCEPROP 2 LASTPIN (-25 3200) $PN 2
J 2
(-35 3210);
DISPLAY 0.617021 (-35 3210);
PAINT ORANGE (-35 3210);
FORCEPROP 2 LASTPIN (-25 3250) $PN 3
J 2
(-35 3260);
DISPLAY 0.617021 (-35 3260);
PAINT ORANGE (-35 3260);
FORCEPROP 2 LASTPIN (-25 3300) $PN 5
J 2
(-35 3310);
DISPLAY 0.617021 (-35 3310);
PAINT ORANGE (-35 3310);
FORCEPROP 2 LASTPIN (-25 3350) $PN 6
J 2
(-35 3360);
DISPLAY 0.617021 (-35 3360);
PAINT ORANGE (-35 3360);
FORCEPROP 2 LASTPIN (-25 3050) $PN 11
J 2
(-35 3060);
DISPLAY 0.617021 (-35 3060);
PAINT ORANGE (-35 3060);
FORCEPROP 2 LASTPIN (-25 3000) $PN 8
J 2
(-35 3010);
DISPLAY 0.617021 (-35 3010);
PAINT ORANGE (-35 3010);
FORCEPROP 2 LASTPIN (-25 2950) $PN 7
J 2
(-35 2960);
DISPLAY 0.617021 (-35 2960);
PAINT ORANGE (-35 2960);
FORCEPROP 1 LAST PACK_TYPE SM
J 2
(825 3950);
PAINT SKYBLUE (825 3950);
DISPLAY INVISIBLE (825 3950);
FORCEPROP 2 LAST ROOM PROC_SIDEBAND
J 2
(825 4000);
PAINT MONO (825 4000);
DISPLAY INVISIBLE (825 4000);
FORCEPROP 2 LAST CDS_LOCATION U2T4
J 2
(825 3900);
DISPLAY 0.617021 (825 3900);
PAINT AQUA (825 3900);
DISPLAY INVISIBLE (825 3900);
FORCEPROP 2 LAST SEC 1
J 0
(825 3950);
DISPLAY 0.680851 (825 3950);
PAINT MONO (825 3950);
DISPLAY INVISIBLE (825 3950);
FORCEPROP 2 LAST SEC_TYPE SM
J 0
(825 3950);
DISPLAY 1.021277 (825 3950);
PAINT ORANGE (825 3950);
DISPLAY INVISIBLE (825 3950);
FORCEPROP 1 LAST PATH I30
J 2
(425 3850);
PAINT GREEN (425 3850);
DISPLAY INVISIBLE (425 3850);
FORCEPROP 2 LAST CDS_LIB mstr_digital
J 2
(425 3350);
PAINT MONO (425 3350);
DISPLAY INVISIBLE (425 3350);
FORCEPROP 2 LAST BOM_COST PROC
J 2
(425 3350);
PAINT MONO (425 3350);
DISPLAY INVISIBLE (425 3350);
FORCEADD RES..1
(2950 2850);
FORCEPROP 1 LAST VALUE 33.2
J 2
(2900 2800);
DISPLAY 0.617021 (2900 2800);
PAINT SKYBLUE (2900 2800);
FORCEPROP 1 LAST PACK_TYPE 0402
J 0
(3000 2800);
DISPLAY 0.617021 (3000 2800);
PAINT SKYBLUE (3000 2800);
FORCEPROP 1 LASTPIN (3050 2850) $PN 2
J 0
(3012 2862);
DISPLAY 0.617021 (3012 2862);
PAINT ORANGE (3012 2862);
FORCEPROP 1 LAST LOCATION R2T38
J 0
(2900 2900);
DISPLAY 0.617021 (2900 2900);
PAINT AQUA (2900 2900);
FORCEPROP 1 LASTPIN (2850 2850) $PN 1
J 0
(2862 2862);
DISPLAY 0.617021 (2862 2862);
PAINT ORANGE (2862 2862);
FORCEPROP 1 LAST TOLERANCE 1%
J 0
(2925 2800);
DISPLAY 0.617021 (2925 2800);
PAINT SKYBLUE (2925 2800);
FORCEPROP 1 LAST MATERIAL CHIP
J 0
(2850 2750);
DISPLAY 0.617021 (2850 2750);
PAINT SKYBLUE (2850 2750);
FORCEPROP 1 LAST WATTAGE 1/16W
J 2
(2825 2750);
DISPLAY 0.617021 (2825 2750);
PAINT SKYBLUE (2825 2750);
FORCEPROP 1 LAST PART_NUMBER G21796-074
J 0
(2950 2750);
DISPLAY 0.617021 (2950 2750);
PAINT BLUE (2950 2750);
FORCEPROP 2 LAST SEC 1
J 0
(2900 3050);
DISPLAY 0.680851 (2900 3050);
PAINT MONO (2900 3050);
DISPLAY INVISIBLE (2900 3050);
FORCEPROP 2 LAST SEC_TYPE 0402
J 0
(2900 3050);
DISPLAY 1.021277 (2900 3050);
PAINT ORANGE (2900 3050);
DISPLAY INVISIBLE (2900 3050);
FORCEPROP 2 LAST CDS_LIB mstr_discrete
J 0
(2950 2850);
PAINT ORANGE (2950 2850);
DISPLAY INVISIBLE (2950 2850);
FORCEPROP 2 LAST BOM_COST PROC
J 2
(2950 2850);
PAINT MONO (2950 2850);
DISPLAY INVISIBLE (2950 2850);
FORCEPROP 1 LAST PATH I39
J 0
(2900 3000);
DISPLAY 0.978723 (2900 3000);
PAINT WHITE (2900 3000);
DISPLAY INVISIBLE (2900 3000);
FORCEPROP 2 LAST CDS_LOCATION R2T38
J 0
(2900 2900);
DISPLAY 0.617021 (2900 2900);
PAINT AQUA (2900 2900);
DISPLAY INVISIBLE (2900 2900);
FORCEPROP 2 LAST ROOM PROC_SIDEBAND
J 0
(2875 2775);
DISPLAY 0.617021 (2875 2775);
PAINT ORANGE (2875 2775);
DISPLAY INVISIBLE (2875 2775);
FORCEADD OFFPAGE..1
(-3400 3200);
FORCEPROP 2 LAST $XR0 55 
J 0
(-3621 3200);
DISPLAY 0.638298 (-3621 3200);
PAINT MONO (-3621 3200);
FORCEPROP 1 LAST OFFPAGE TRUE
J 0
(-3075 3075);
PAINT GREEN (-3075 3075);
DISPLAY INVISIBLE (-3075 3075);
FORCEPROP 1 LAST COMMENT_BODY TRUE
J 0
(-3275 3100);
DISPLAY 1.170213 (-3275 3100);
PAINT GREEN (-3275 3100);
DISPLAY INVISIBLE (-3275 3100);
FORCEPROP 2 LAST CDS_LIB mstr_standard
J 0
(-3400 3200);
PAINT ORANGE (-3400 3200);
DISPLAY INVISIBLE (-3400 3200);
FORCEPROP 2 LAST PATH I4
J 0
(-3650 3250);
DISPLAY 1.021277 (-3650 3250);
PAINT ORANGE (-3650 3250);
DISPLAY INVISIBLE (-3650 3250);
FORCEADD RES..1
(2950 3100);
FORCEPROP 1 LAST WATTAGE 1/16W
J 2
(2825 3000);
DISPLAY 0.617021 (2825 3000);
PAINT SKYBLUE (2825 3000);
FORCEPROP 1 LAST PACK_TYPE 0402
J 0
(3000 3050);
DISPLAY 0.617021 (3000 3050);
PAINT SKYBLUE (3000 3050);
FORCEPROP 1 LASTPIN (3050 3100) $PN 2
J 0
(3012 3112);
DISPLAY 0.617021 (3012 3112);
PAINT ORANGE (3012 3112);
FORCEPROP 1 LAST LOCATION R2T33
J 0
(2900 3150);
DISPLAY 0.617021 (2900 3150);
PAINT AQUA (2900 3150);
FORCEPROP 1 LASTPIN (2850 3100) $PN 1
J 0
(2862 3112);
DISPLAY 0.617021 (2862 3112);
PAINT ORANGE (2862 3112);
FORCEPROP 1 LAST TOLERANCE 1%
J 0
(2925 3050);
DISPLAY 0.617021 (2925 3050);
PAINT SKYBLUE (2925 3050);
FORCEPROP 1 LAST VALUE 33.2
J 2
(2900 3050);
DISPLAY 0.617021 (2900 3050);
PAINT SKYBLUE (2900 3050);
FORCEPROP 1 LAST PART_NUMBER G21796-074
J 0
(2950 3000);
DISPLAY 0.617021 (2950 3000);
PAINT BLUE (2950 3000);
FORCEPROP 1 LAST MATERIAL CHIP
J 0
(2850 3000);
DISPLAY 0.617021 (2850 3000);
PAINT SKYBLUE (2850 3000);
FORCEPROP 2 LAST SEC 1
J 0
(2900 3300);
DISPLAY 0.680851 (2900 3300);
PAINT MONO (2900 3300);
DISPLAY INVISIBLE (2900 3300);
FORCEPROP 2 LAST SEC_TYPE 0402
J 0
(2900 3300);
DISPLAY 1.021277 (2900 3300);
PAINT ORANGE (2900 3300);
DISPLAY INVISIBLE (2900 3300);
FORCEPROP 2 LAST BOM_COST PROC
J 2
(2950 3100);
PAINT MONO (2950 3100);
DISPLAY INVISIBLE (2950 3100);
FORCEPROP 2 LAST CDS_LIB mstr_discrete
J 0
(2950 3100);
PAINT ORANGE (2950 3100);
DISPLAY INVISIBLE (2950 3100);
FORCEPROP 1 LAST PATH I40
J 0
(2900 3250);
DISPLAY 0.978723 (2900 3250);
PAINT WHITE (2900 3250);
DISPLAY INVISIBLE (2900 3250);
FORCEPROP 2 LAST CDS_LOCATION R2T33
J 0
(2900 3150);
DISPLAY 0.617021 (2900 3150);
PAINT AQUA (2900 3150);
DISPLAY INVISIBLE (2900 3150);
FORCEPROP 2 LAST ROOM PROC_SIDEBAND
J 0
(2875 3025);
DISPLAY 0.617021 (2875 3025);
PAINT ORANGE (2875 3025);
DISPLAY INVISIBLE (2875 3025);
FORCEADD RES..1
(2950 3350);
FORCEPROP 1 LASTPIN (2850 3350) $PN 1
J 0
(2862 3362);
DISPLAY 0.617021 (2862 3362);
PAINT ORANGE (2862 3362);
FORCEPROP 1 LAST LOCATION R2T30
J 0
(2900 3400);
DISPLAY 0.617021 (2900 3400);
PAINT AQUA (2900 3400);
FORCEPROP 1 LAST PACK_TYPE 0402
J 0
(3000 3300);
DISPLAY 0.617021 (3000 3300);
PAINT SKYBLUE (3000 3300);
FORCEPROP 1 LAST PART_NUMBER G21796-074
J 0
(2950 3250);
DISPLAY 0.617021 (2950 3250);
PAINT BLUE (2950 3250);
FORCEPROP 1 LASTPIN (3050 3350) $PN 2
J 0
(3012 3362);
DISPLAY 0.617021 (3012 3362);
PAINT ORANGE (3012 3362);
FORCEPROP 1 LAST TOLERANCE 1%
J 0
(2925 3300);
DISPLAY 0.617021 (2925 3300);
PAINT SKYBLUE (2925 3300);
FORCEPROP 1 LAST MATERIAL CHIP
J 0
(2850 3250);
DISPLAY 0.617021 (2850 3250);
PAINT SKYBLUE (2850 3250);
FORCEPROP 1 LAST WATTAGE 1/16W
J 2
(2825 3250);
DISPLAY 0.617021 (2825 3250);
PAINT SKYBLUE (2825 3250);
FORCEPROP 1 LAST VALUE 33.2
J 2
(2900 3300);
DISPLAY 0.617021 (2900 3300);
PAINT SKYBLUE (2900 3300);
FORCEPROP 2 LAST SEC_TYPE 0402
J 0
(2900 3550);
DISPLAY 1.021277 (2900 3550);
PAINT ORANGE (2900 3550);
DISPLAY INVISIBLE (2900 3550);
FORCEPROP 2 LAST CDS_LIB mstr_discrete
J 0
(2950 3350);
PAINT ORANGE (2950 3350);
DISPLAY INVISIBLE (2950 3350);
FORCEPROP 2 LAST BOM_COST PROC
J 2
(2950 3350);
PAINT MONO (2950 3350);
DISPLAY INVISIBLE (2950 3350);
FORCEPROP 1 LAST PATH I42
J 0
(2900 3500);
DISPLAY 0.978723 (2900 3500);
PAINT WHITE (2900 3500);
DISPLAY INVISIBLE (2900 3500);
FORCEPROP 2 LAST CDS_LOCATION R2T30
J 0
(2900 3400);
DISPLAY 0.617021 (2900 3400);
PAINT AQUA (2900 3400);
DISPLAY INVISIBLE (2900 3400);
FORCEPROP 2 LAST SEC 1
J 0
(2900 3550);
DISPLAY 0.680851 (2900 3550);
PAINT MONO (2900 3550);
DISPLAY INVISIBLE (2900 3550);
FORCEPROP 2 LAST ROOM PROC_SIDEBAND
J 0
(2875 3275);
DISPLAY 0.617021 (2875 3275);
PAINT ORANGE (2875 3275);
DISPLAY INVISIBLE (2875 3275);
FORCEADD OFFPAGE..5
R 2
(3650 3100);
FORCEPROP 2 LAST $XR0 93 
J 0
(3839 3100);
DISPLAY 0.638298 (3839 3100);
PAINT MONO (3839 3100);
FORCEPROP 2 LAST PATH I47
J 0
(3850 3150);
DISPLAY 1.021277 (3850 3150);
PAINT ORANGE (3850 3150);
DISPLAY INVISIBLE (3850 3150);
FORCEPROP 2 LAST CDS_LIB mstr_standard
J 0
(3650 3100);
PAINT ORANGE (3650 3100);
DISPLAY INVISIBLE (3650 3100);
FORCEPROP 1 LAST COMMENT_BODY TRUE
J 2
(3550 3025);
DISPLAY 1.170213 (3550 3025);
PAINT GREEN (3550 3025);
DISPLAY INVISIBLE (3550 3025);
FORCEPROP 1 LAST OFFPAGE TRUE
J 2
(3325 2975);
PAINT GREEN (3325 2975);
DISPLAY INVISIBLE (3325 2975);
FORCEADD OFFPAGE..2
(3650 3350);
FORCEPROP 2 LAST $XR0 93 
J 0
(3839 3350);
DISPLAY 0.638298 (3839 3350);
PAINT MONO (3839 3350);
FORCEPROP 1 LAST OFFPAGE TRUE
J 0
(3975 3225);
PAINT GREEN (3975 3225);
DISPLAY INVISIBLE (3975 3225);
FORCEPROP 2 LAST PATH I48
J 0
(3850 3400);
DISPLAY 1.021277 (3850 3400);
PAINT ORANGE (3850 3400);
DISPLAY INVISIBLE (3850 3400);
FORCEPROP 2 LAST CDS_LIB mstr_standard
J 0
(3650 3350);
PAINT MONO (3650 3350);
DISPLAY INVISIBLE (3650 3350);
FORCEPROP 1 LAST COMMENT_BODY TRUE
J 0
(3605 3255);
DISPLAY 1.085106 (3605 3255);
PAINT GREEN (3605 3255);
DISPLAY INVISIBLE (3605 3255);
FORCEADD OFFPAGE..1
(-3400 3725);
FORCEPROP 2 LAST $XR0 55 
J 0
(-3621 3725);
DISPLAY 0.638298 (-3621 3725);
PAINT MONO (-3621 3725);
FORCEPROP 1 LAST OFFPAGE TRUE
J 0
(-3075 3600);
PAINT GREEN (-3075 3600);
DISPLAY INVISIBLE (-3075 3600);
FORCEPROP 1 LAST COMMENT_BODY TRUE
J 0
(-3275 3625);
DISPLAY 1.170213 (-3275 3625);
PAINT GREEN (-3275 3625);
DISPLAY INVISIBLE (-3275 3625);
FORCEPROP 2 LAST CDS_LIB mstr_standard
J 0
(-3400 3725);
PAINT ORANGE (-3400 3725);
DISPLAY INVISIBLE (-3400 3725);
FORCEPROP 2 LAST PATH I5
J 0
(-3650 3775);
DISPLAY 1.021277 (-3650 3775);
PAINT ORANGE (-3650 3775);
DISPLAY INVISIBLE (-3650 3775);
FORCEADD OFFPAGE..1
(-3400 3425);
FORCEPROP 2 LAST $XR0 21 
J 0
(-3621 3425);
DISPLAY 0.638298 (-3621 3425);
PAINT MONO (-3621 3425);
FORCEPROP 1 LAST OFFPAGE TRUE
J 0
(-3075 3300);
PAINT GREEN (-3075 3300);
DISPLAY INVISIBLE (-3075 3300);
FORCEPROP 1 LAST COMMENT_BODY TRUE
J 0
(-3275 3325);
DISPLAY 1.170213 (-3275 3325);
PAINT GREEN (-3275 3325);
DISPLAY INVISIBLE (-3275 3325);
FORCEPROP 2 LAST CDS_LIB mstr_standard
J 0
(-3400 3425);
PAINT ORANGE (-3400 3425);
DISPLAY INVISIBLE (-3400 3425);
FORCEPROP 2 LAST PATH I6
J 0
(-3600 3475);
DISPLAY 1.021277 (-3600 3475);
PAINT ORANGE (-3600 3475);
DISPLAY INVISIBLE (-3600 3475);
FORCEADD RES..1
(2950 2575);
FORCEPROP 1 LAST VALUE 33.2
J 2
(2900 2525);
DISPLAY 0.617021 (2900 2525);
PAINT SKYBLUE (2900 2525);
FORCEPROP 1 LAST LOCATION R7D24
J 0
(2900 2625);
DISPLAY 0.617021 (2900 2625);
PAINT AQUA (2900 2625);
FORCEPROP 1 LASTPIN (3050 2575) $PN 2
J 0
(3012 2587);
DISPLAY 0.617021 (3012 2587);
PAINT ORANGE (3012 2587);
FORCEPROP 1 LASTPIN (2850 2575) $PN 1
J 0
(2862 2587);
DISPLAY 0.617021 (2862 2587);
PAINT ORANGE (2862 2587);
FORCEPROP 1 LAST WATTAGE 1/16W
J 2
(2825 2475);
DISPLAY 0.617021 (2825 2475);
PAINT SKYBLUE (2825 2475);
FORCEPROP 1 LAST TOLERANCE 1%
J 0
(2925 2525);
DISPLAY 0.617021 (2925 2525);
PAINT SKYBLUE (2925 2525);
FORCEPROP 1 LAST PACK_TYPE 0402
J 0
(3000 2525);
DISPLAY 0.617021 (3000 2525);
PAINT SKYBLUE (3000 2525);
FORCEPROP 1 LAST PART_NUMBER G21796-074
J 0
(2950 2475);
DISPLAY 0.617021 (2950 2475);
PAINT BLUE (2950 2475);
FORCEPROP 1 LAST MATERIAL CHIP
J 0
(2850 2475);
DISPLAY 0.617021 (2850 2475);
PAINT SKYBLUE (2850 2475);
FORCEPROP 2 LAST SEC_TYPE 0402
J 0
(2900 2775);
DISPLAY 1.021277 (2900 2775);
PAINT ORANGE (2900 2775);
DISPLAY INVISIBLE (2900 2775);
FORCEPROP 2 LAST CDS_LIB mstr_discrete
J 0
(2950 2575);
PAINT ORANGE (2950 2575);
DISPLAY INVISIBLE (2950 2575);
FORCEPROP 2 LAST BOM_COST PROC
J 2
(2950 2575);
PAINT MONO (2950 2575);
DISPLAY INVISIBLE (2950 2575);
FORCEPROP 1 LAST PATH I62
J 0
(2900 2725);
DISPLAY 0.978723 (2900 2725);
PAINT WHITE (2900 2725);
DISPLAY INVISIBLE (2900 2725);
FORCEPROP 2 LAST CDS_LOCATION R7D24
J 0
(2900 2625);
DISPLAY 0.617021 (2900 2625);
PAINT AQUA (2900 2625);
DISPLAY INVISIBLE (2900 2625);
FORCEPROP 2 LAST SEC 1
J 0
(2900 2775);
DISPLAY 0.680851 (2900 2775);
PAINT MONO (2900 2775);
DISPLAY INVISIBLE (2900 2775);
FORCEPROP 2 LAST ROOM PROC_SIDEBAND
J 0
(2875 2500);
DISPLAY 0.617021 (2875 2500);
PAINT ORANGE (2875 2500);
DISPLAY INVISIBLE (2875 2500);
FORCEADD RES..2
(-2325 4050);
FORCEPROP 1 LAST LOCATION R2T19
J 0
(-2280 4175);
DISPLAY 0.617021 (-2280 4175);
PAINT AQUA (-2280 4175);
FORCEPROP 1 LASTPIN (-2325 4150) $PN 1
J 0
(-2320 4112);
DISPLAY 0.617021 (-2320 4112);
PAINT ORANGE (-2320 4112);
FORCEPROP 1 LAST TOLERANCE 1%
J 0
(-2280 4075);
DISPLAY 0.617021 (-2280 4075);
PAINT SKYBLUE (-2280 4075);
FORCEPROP 1 LAST PACK_TYPE 0402
J 0
(-2160 3975);
DISPLAY 0.617021 (-2160 3975);
PAINT SKYBLUE (-2160 3975);
FORCEPROP 1 LAST PART_NUMBER G21796-004
J 0
(-2285 3925);
DISPLAY 0.617021 (-2285 3925);
PAINT BLUE (-2285 3925);
FORCEPROP 1 LAST MATERIAL CHIP
J 0
(-2285 3975);
DISPLAY 0.617021 (-2285 3975);
PAINT SKYBLUE (-2285 3975);
FORCEPROP 1 LAST WATTAGE 1/16W
J 0
(-2285 4025);
DISPLAY 0.617021 (-2285 4025);
PAINT SKYBLUE (-2285 4025);
FORCEPROP 1 LASTPIN (-2325 3950) $PN 2
J 0
(-2320 3960);
DISPLAY 0.617021 (-2320 3960);
PAINT ORANGE (-2320 3960);
FORCEPROP 1 LAST VALUE 200.0
J 0
(-2280 4125);
DISPLAY 0.617021 (-2280 4125);
PAINT SKYBLUE (-2280 4125);
FORCEPROP 1 LAST PATH I63
J 0
(-2275 4225);
DISPLAY 0.978723 (-2275 4225);
PAINT WHITE (-2275 4225);
DISPLAY INVISIBLE (-2275 4225);
FORCEPROP 2 LAST CDS_LOCATION R2T19
J 0
(-2280 4175);
DISPLAY 0.617021 (-2280 4175);
PAINT AQUA (-2280 4175);
DISPLAY INVISIBLE (-2280 4175);
FORCEPROP 2 LAST SEC 1
J 0
(-2275 4275);
DISPLAY 0.680851 (-2275 4275);
PAINT MONO (-2275 4275);
DISPLAY INVISIBLE (-2275 4275);
FORCEPROP 2 LAST SEC_TYPE 0402
J 0
(-2275 4275);
DISPLAY 1.021277 (-2275 4275);
PAINT ORANGE (-2275 4275);
DISPLAY INVISIBLE (-2275 4275);
FORCEPROP 2 LAST ROOM PROC_SIDEBAND
J 0
(-2300 3825);
PAINT ORANGE (-2300 3825);
DISPLAY INVISIBLE (-2300 3825);
FORCEPROP 2 LAST BOM_COST PROC
J 0
(-2325 4050);
PAINT MONO (-2325 4050);
DISPLAY INVISIBLE (-2325 4050);
FORCEPROP 2 LAST CDS_LIB mstr_discrete
J 0
(-2325 4050);
PAINT MONO (-2325 4050);
DISPLAY INVISIBLE (-2325 4050);
FORCEADD PVCCIO_CPU0..1
(-2325 4300);
FORCEPROP 3 LASTPIN (-2325 4250) SIG_NAME PVCCIO_CPU0\g
J 0
(-2315 4260);
DISPLAY 0.659574 (-2315 4260);
PAINT MONO (-2315 4260);
DISPLAY INVISIBLE (-2315 4260);
FORCEPROP 1 LAST PATH I64
J 0
(-2275 4325);
DISPLAY 0.872340 (-2275 4325);
PAINT AQUA (-2275 4325);
DISPLAY INVISIBLE (-2275 4325);
FORCEPROP 1 LAST HDL_POWER PVCCIO_CPU0
J 1
(-2325 4350);
DISPLAY 0.872340 (-2325 4350);
PAINT GREEN (-2325 4350);
DISPLAY INVISIBLE (-2325 4350);
FORCEPROP 1 LAST VOLTAGE 1.1V
J 0
(-2370 4257);
DISPLAY 0.340426 (-2370 4257);
PAINT SKYBLUE (-2370 4257);
DISPLAY INVISIBLE (-2370 4257);
FORCEPROP 2 LAST CDS_LIB mstr_symbols
J 0
(-2325 4300);
PAINT ORANGE (-2325 4300);
DISPLAY INVISIBLE (-2325 4300);
FORCEPROP 1 LAST BODY_TYPE PLUMBING
J 0
(-2370 4257);
DISPLAY 0.340426 (-2370 4257);
PAINT GREEN (-2370 4257);
DISPLAY INVISIBLE (-2370 4257);
FORCEADD RES..1
(-925 3825);
FORCEPROP 1 LAST LOCATION R2T16
J 0
(-975 3875);
DISPLAY 0.617021 (-975 3875);
PAINT AQUA (-975 3875);
FORCEPROP 1 LASTPIN (-1025 3825) $PN 1
J 0
(-1013 3837);
DISPLAY 0.617021 (-1013 3837);
PAINT ORANGE (-1013 3837);
FORCEPROP 1 LASTPIN (-825 3825) $PN 2
J 0
(-863 3837);
DISPLAY 0.617021 (-863 3837);
PAINT ORANGE (-863 3837);
FORCEPROP 1 LAST TOLERANCE 1.0%
J 0
(-925 3725);
DISPLAY 0.617021 (-925 3725);
PAINT SKYBLUE (-925 3725);
FORCEPROP 1 LAST PACK_TYPE 0402
J 0
(-1000 3625);
DISPLAY 0.617021 (-1000 3625);
PAINT SKYBLUE (-1000 3625);
FORCEPROP 1 LAST MATERIAL CHIP
J 0
(-925 3675);
DISPLAY 0.617021 (-925 3675);
PAINT SKYBLUE (-925 3675);
FORCEPROP 1 LAST VALUE 75
J 2
(-950 3725);
DISPLAY 0.617021 (-950 3725);
PAINT SKYBLUE (-950 3725);
FORCEPROP 1 LAST WATTAGE 1/16W
J 2
(-950 3675);
DISPLAY 0.617021 (-950 3675);
PAINT SKYBLUE (-950 3675);
FORCEPROP 1 LAST PART_NUMBER G21796-267
J 0
(-900 3625);
DISPLAY 0.617021 (-900 3625);
PAINT BLUE (-900 3625);
FORCEPROP 0 LAST ROOM PROC_SIDEBAND
J 0
(-975 4025);
DISPLAY 1.021277 (-975 4025);
PAINT ORANGE (-975 4025);
DISPLAY INVISIBLE (-975 4025);
FORCEPROP 1 LAST PATH I67
J 0
(-975 3975);
DISPLAY 0.978723 (-975 3975);
PAINT WHITE (-975 3975);
DISPLAY INVISIBLE (-975 3975);
FORCEPROP 2 LAST CDS_LOCATION R2T16
J 0
(-975 3875);
DISPLAY 0.617021 (-975 3875);
PAINT AQUA (-975 3875);
DISPLAY INVISIBLE (-975 3875);
FORCEPROP 2 LAST SEC 1
J 0
(-975 4025);
DISPLAY 0.680851 (-975 4025);
PAINT MONO (-975 4025);
DISPLAY INVISIBLE (-975 4025);
FORCEPROP 2 LAST SEC_TYPE 0402
J 0
(-975 4025);
DISPLAY 1.021277 (-975 4025);
PAINT ORANGE (-975 4025);
DISPLAY INVISIBLE (-975 4025);
FORCEPROP 2 LAST CDS_LIB mstr_discrete
J 0
(-925 3825);
PAINT MONO (-925 3825);
DISPLAY INVISIBLE (-925 3825);
FORCEADD RES..1
(-925 3300);
FORCEPROP 1 LAST LOCATION R2T31
J 0
(-975 3350);
DISPLAY 0.617021 (-975 3350);
PAINT AQUA (-975 3350);
FORCEPROP 1 LASTPIN (-825 3300) $PN 2
J 0
(-863 3312);
DISPLAY 0.617021 (-863 3312);
PAINT ORANGE (-863 3312);
FORCEPROP 1 LAST VALUE 75
J 2
(-900 3225);
DISPLAY 0.617021 (-900 3225);
PAINT SKYBLUE (-900 3225);
FORCEPROP 1 LAST TOLERANCE 1.0%
J 0
(-1125 3175);
DISPLAY 0.617021 (-1125 3175);
PAINT SKYBLUE (-1125 3175);
FORCEPROP 1 LAST MATERIAL CHIP
J 0
(-1075 3125);
DISPLAY 0.617021 (-1075 3125);
PAINT SKYBLUE (-1075 3125);
FORCEPROP 1 LASTPIN (-1025 3300) $PN 1
J 0
(-1013 3312);
DISPLAY 0.617021 (-1013 3312);
PAINT ORANGE (-1013 3312);
FORCEPROP 1 LAST WATTAGE 1/16W
J 2
(-875 3175);
DISPLAY 0.617021 (-875 3175);
PAINT SKYBLUE (-875 3175);
FORCEPROP 1 LAST PART_NUMBER G21796-267
J 0
(-950 3125);
DISPLAY 0.617021 (-950 3125);
PAINT BLUE (-950 3125);
FORCEPROP 1 LAST PACK_TYPE 0402
J 0
(-1125 3225);
DISPLAY 0.617021 (-1125 3225);
PAINT SKYBLUE (-1125 3225);
FORCEPROP 2 LAST SEC 1
J 0
(-975 3500);
DISPLAY 0.680851 (-975 3500);
PAINT MONO (-975 3500);
DISPLAY INVISIBLE (-975 3500);
FORCEPROP 1 LAST PATH I68
J 0
(-975 3450);
DISPLAY 0.978723 (-975 3450);
PAINT WHITE (-975 3450);
DISPLAY INVISIBLE (-975 3450);
FORCEPROP 2 LAST CDS_LOCATION R2T31
J 0
(-975 3350);
DISPLAY 0.617021 (-975 3350);
PAINT AQUA (-975 3350);
DISPLAY INVISIBLE (-975 3350);
FORCEPROP 2 LAST SEC_TYPE 0402
J 0
(-975 3500);
DISPLAY 1.021277 (-975 3500);
PAINT ORANGE (-975 3500);
DISPLAY INVISIBLE (-975 3500);
FORCEPROP 0 LAST ROOM PROC_SIDEBAND
J 0
(-975 3450);
DISPLAY 1.021277 (-975 3450);
PAINT ORANGE (-975 3450);
DISPLAY INVISIBLE (-975 3450);
FORCEPROP 2 LAST CDS_LIB mstr_discrete
J 0
(-925 3300);
PAINT MONO (-925 3300);
DISPLAY INVISIBLE (-925 3300);
FORCEADD P3V3..1
(1000 4150);
FORCEPROP 3 LASTPIN (1000 4100) SIG_NAME P3V3\g
J 0
(1010 4110);
DISPLAY 0.659574 (1010 4110);
PAINT MONO (1010 4110);
DISPLAY INVISIBLE (1010 4110);
FORCEPROP 1 LAST HDL_POWER P3V3
J 0
(675 4025);
DISPLAY 0.872340 (675 4025);
PAINT ORANGE (675 4025);
DISPLAY INVISIBLE (675 4025);
FORCEPROP 2 LAST CDS_LIB mstr_symbols
J 0
(1000 4150);
PAINT ORANGE (1000 4150);
DISPLAY INVISIBLE (1000 4150);
FORCEPROP 1 LAST VOLTAGE 3.3V
J 0
(955 4107);
DISPLAY 0.340426 (955 4107);
PAINT SKYBLUE (955 4107);
DISPLAY INVISIBLE (955 4107);
FORCEPROP 1 LAST BODY_TYPE PLUMBING
J 0
(955 4107);
DISPLAY 0.340426 (955 4107);
PAINT GREEN (955 4107);
DISPLAY INVISIBLE (955 4107);
FORCEPROP 1 LAST SIZE 1B
J 0
(1045 4172);
DISPLAY 0.340426 (1045 4172);
PAINT GREEN (1045 4172);
DISPLAY INVISIBLE (1045 4172);
FORCEPROP 1 LAST PATH I70
J 0
(1045 4152);
DISPLAY 0.340426 (1045 4152);
PAINT GREEN (1045 4152);
DISPLAY INVISIBLE (1045 4152);
FORCEADD CAP_A..1
(1150 3875);
FORCEPROP 1 LAST MATERIAL X6S
J 0
(1200 3775);
DISPLAY 0.617021 (1200 3775);
PAINT SKYBLUE (1200 3775);
FORCEPROP 1 LAST VOLTAGE 6.3V
J 0
(1200 3875);
DISPLAY 0.617021 (1200 3875);
PAINT SKYBLUE (1200 3875);
FORCEPROP 1 LAST PACK_TYPE 0402V
J 0
(1200 3675);
DISPLAY 0.617021 (1200 3675);
PAINT SKYBLUE (1200 3675);
FORCEPROP 1 LAST TOLERANCE 10%
J 0
(1200 3825);
DISPLAY 0.617021 (1200 3825);
PAINT SKYBLUE (1200 3825);
FORCEPROP 1 LAST VALUE 1.0UF
J 0
(1200 3925);
DISPLAY 0.617021 (1200 3925);
PAINT SKYBLUE (1200 3925);
FORCEPROP 1 LAST PART_NUMBER D97712-004
J 0
(1200 3725);
DISPLAY 0.617021 (1200 3725);
PAINT BLUE (1200 3725);
FORCEPROP 1 LAST LOCATION C2T33
J 0
(1200 3975);
DISPLAY 0.617021 (1200 3975);
PAINT AQUA (1200 3975);
FORCEPROP 1 LASTPIN (1150 3975) $PN 1
J 0
(1160 3955);
DISPLAY 0.617021 (1160 3955);
PAINT MONO (1160 3955);
FORCEPROP 1 LASTPIN (1150 3775) $PN 2
J 0
(1160 3755);
DISPLAY 0.617021 (1160 3755);
PAINT MONO (1160 3755);
FORCEPROP 2 LAST SEC 1
J 0
(1200 4075);
DISPLAY 0.936170 (1200 4075);
PAINT MONO (1200 4075);
DISPLAY INVISIBLE (1200 4075);
FORCEPROP 2 LAST SEC_TYPE 0402V
J 0
(1200 4075);
PAINT MONO (1200 4075);
DISPLAY INVISIBLE (1200 4075);
FORCEPROP 1 LAST PATH I72
J 0
(1200 4025);
DISPLAY 0.978723 (1200 4025);
PAINT WHITE (1200 4025);
DISPLAY INVISIBLE (1200 4025);
FORCEPROP 2 LAST CDS_SEC 1
J 0
(1200 4025);
PAINT ORANGE (1200 4025);
DISPLAY INVISIBLE (1200 4025);
FORCEPROP 2 LAST CDS_LIB dev_discrete
J 0
(1150 3875);
PAINT ORANGE (1150 3875);
DISPLAY INVISIBLE (1150 3875);
FORCEPROP 2 LAST BOM_COST PROC
J 0
(1150 3875);
PAINT MONO (1150 3875);
DISPLAY INVISIBLE (1150 3875);
FORCEPROP 2 LAST CDS_LOCATION C2T33
J 0
(1200 3975);
DISPLAY 0.617021 (1200 3975);
PAINT AQUA (1200 3975);
DISPLAY INVISIBLE (1200 3975);
FORCEPROP 2 LAST ROOM PROC_SIDEBAND
J 0
(1200 3625);
PAINT ORANGE (1200 3625);
DISPLAY INVISIBLE (1200 3625);
FORCEADD GND..1
(1150 3675);
FORCEPROP 3 LASTPIN (1150 3725) SIG_NAME GND\g
J 0
(1160 3735);
DISPLAY 0.659574 (1160 3735);
PAINT MONO (1160 3735);
DISPLAY INVISIBLE (1160 3735);
FORCEPROP 1 LAST HDL_POWER GND
J 0
(1150 3825);
DISPLAY 1.170213 (1150 3825);
PAINT GREEN (1150 3825);
DISPLAY INVISIBLE (1150 3825);
FORCEPROP 1 LAST SIZE 1B
J 0
(1225 3625);
DISPLAY 1.170213 (1225 3625);
PAINT GREEN (1225 3625);
DISPLAY INVISIBLE (1225 3625);
FORCEPROP 1 LAST PATH I73
J 0
(1225 3675);
DISPLAY 0.872340 (1225 3675);
PAINT AQUA (1225 3675);
DISPLAY INVISIBLE (1225 3675);
FORCEPROP 1 LAST VOLTAGE 0
J 0
(1150 3675);
PAINT SKYBLUE (1150 3675);
DISPLAY INVISIBLE (1150 3675);
FORCEPROP 2 LAST CDS_LIB mstr_symbols
J 0
(1150 3675);
PAINT ORANGE (1150 3675);
DISPLAY INVISIBLE (1150 3675);
FORCEPROP 1 LAST BODY_TYPE PLUMBING
J 0
(1105 3632);
DISPLAY 0.340426 (1105 3632);
PAINT GREEN (1105 3632);
DISPLAY INVISIBLE (1105 3632);
FORCEADD OFFPAGE..5
R 2
(3650 2575);
FORCEPROP 2 LAST $XR0 93 
J 0
(3839 2575);
DISPLAY 0.638298 (3839 2575);
PAINT MONO (3839 2575);
FORCEPROP 2 LAST PATH I76
J 0
(3975 2625);
DISPLAY 1.021277 (3975 2625);
PAINT ORANGE (3975 2625);
DISPLAY INVISIBLE (3975 2625);
FORCEPROP 2 LAST CDS_LIB mstr_standard
J 0
(3650 2575);
PAINT ORANGE (3650 2575);
DISPLAY INVISIBLE (3650 2575);
FORCEPROP 1 LAST OFFPAGE TRUE
J 2
(3325 2450);
PAINT GREEN (3325 2450);
DISPLAY INVISIBLE (3325 2450);
FORCEPROP 1 LAST COMMENT_BODY TRUE
J 2
(3550 2500);
DISPLAY 1.170213 (3550 2500);
PAINT GREEN (3550 2500);
DISPLAY INVISIBLE (3550 2500);
FORCEADD OFFPAGE..5
R 2
(3650 2850);
FORCEPROP 2 LAST $XR0 93 
J 0
(3839 2850);
DISPLAY 0.638298 (3839 2850);
PAINT MONO (3839 2850);
FORCEPROP 2 LAST PATH I77
J 0
(3975 2900);
DISPLAY 1.021277 (3975 2900);
PAINT ORANGE (3975 2900);
DISPLAY INVISIBLE (3975 2900);
FORCEPROP 2 LAST CDS_LIB mstr_standard
J 0
(3650 2850);
PAINT ORANGE (3650 2850);
DISPLAY INVISIBLE (3650 2850);
FORCEPROP 1 LAST OFFPAGE TRUE
J 2
(3325 2725);
PAINT GREEN (3325 2725);
DISPLAY INVISIBLE (3325 2725);
FORCEPROP 1 LAST COMMENT_BODY TRUE
J 2
(3550 2775);
DISPLAY 1.170213 (3550 2775);
PAINT GREEN (3550 2775);
DISPLAY INVISIBLE (3550 2775);
FORCEADD PVCCIO_CPU0..1
(-2750 2800);
FORCEPROP 3 LASTPIN (-2750 2750) SIG_NAME PVCCIO_CPU0\g
J 0
(-2740 2760);
DISPLAY 0.659574 (-2740 2760);
PAINT MONO (-2740 2760);
DISPLAY INVISIBLE (-2740 2760);
FORCEPROP 1 LAST HDL_POWER PVCCIO_CPU0
J 1
(-2750 2850);
DISPLAY 0.872340 (-2750 2850);
PAINT GREEN (-2750 2850);
DISPLAY INVISIBLE (-2750 2850);
FORCEPROP 1 LAST PATH I78
J 0
(-2700 2825);
DISPLAY 0.872340 (-2700 2825);
PAINT AQUA (-2700 2825);
DISPLAY INVISIBLE (-2700 2825);
FORCEPROP 2 LAST CDS_LIB mstr_symbols
J 0
(-2750 2800);
PAINT ORANGE (-2750 2800);
DISPLAY INVISIBLE (-2750 2800);
FORCEPROP 1 LAST BODY_TYPE PLUMBING
J 0
(-2795 2757);
DISPLAY 0.340426 (-2795 2757);
PAINT GREEN (-2795 2757);
DISPLAY INVISIBLE (-2795 2757);
FORCEPROP 1 LAST VOLTAGE 1.1V
J 0
(-2795 2757);
DISPLAY 0.340426 (-2795 2757);
PAINT SKYBLUE (-2795 2757);
DISPLAY INVISIBLE (-2795 2757);
FORCEADD RES..2
(-2750 2525);
FORCEPROP 1 LAST PART_NUMBER G21796-009
J 0
(-2710 2400);
DISPLAY 0.617021 (-2710 2400);
PAINT BLUE (-2710 2400);
FORCEPROP 1 LAST VALUE 150.0
J 0
(-2705 2600);
DISPLAY 0.617021 (-2705 2600);
PAINT SKYBLUE (-2705 2600);
FORCEPROP 1 LAST LOCATION R4R3
J 0
(-2705 2650);
DISPLAY 0.617021 (-2705 2650);
PAINT AQUA (-2705 2650);
FORCEPROP 1 LASTPIN (-2750 2625) $PN 1
J 0
(-2745 2587);
DISPLAY 0.617021 (-2745 2587);
PAINT ORANGE (-2745 2587);
FORCEPROP 1 LAST TOLERANCE 1%
J 0
(-2705 2550);
DISPLAY 0.617021 (-2705 2550);
PAINT SKYBLUE (-2705 2550);
FORCEPROP 1 LASTPIN (-2750 2425) $PN 2
J 0
(-2745 2435);
DISPLAY 0.617021 (-2745 2435);
PAINT ORANGE (-2745 2435);
FORCEPROP 1 LAST WATTAGE 1/16W
J 0
(-2710 2500);
DISPLAY 0.617021 (-2710 2500);
PAINT SKYBLUE (-2710 2500);
FORCEPROP 1 LAST MATERIAL CHIP
J 0
(-2710 2450);
DISPLAY 0.617021 (-2710 2450);
PAINT SKYBLUE (-2710 2450);
FORCEPROP 1 LAST PACK_TYPE 0402
J 0
(-2710 2350);
DISPLAY 0.617021 (-2710 2350);
PAINT SKYBLUE (-2710 2350);
FORCEPROP 2 LAST SEC_TYPE 0402
J 0
(-2700 2750);
DISPLAY 1.021277 (-2700 2750);
PAINT ORANGE (-2700 2750);
DISPLAY INVISIBLE (-2700 2750);
FORCEPROP 2 LAST SEC 1
J 0
(-2700 2750);
DISPLAY 0.680851 (-2700 2750);
PAINT MONO (-2700 2750);
DISPLAY INVISIBLE (-2700 2750);
FORCEPROP 1 LAST PATH I79
J 0
(-2700 2700);
DISPLAY 0.978723 (-2700 2700);
PAINT WHITE (-2700 2700);
DISPLAY INVISIBLE (-2700 2700);
FORCEPROP 2 LAST CDS_LOCATION R4R3
J 0
(-2705 2650);
DISPLAY 0.617021 (-2705 2650);
PAINT AQUA (-2705 2650);
DISPLAY INVISIBLE (-2705 2650);
FORCEPROP 2 LAST BOM_COST PROC_SIDEBAND
J 0
(-2750 2525);
PAINT MONO (-2750 2525);
DISPLAY INVISIBLE (-2750 2525);
FORCEPROP 2 LAST CDS_LIB mstr_discrete
J 0
(-2750 2525);
PAINT MONO (-2750 2525);
DISPLAY INVISIBLE (-2750 2525);
FORCEPROP 2 LAST ROOM PROC_SIDEBAND
J 0
(-2725 2300);
PAINT ORANGE (-2725 2300);
DISPLAY INVISIBLE (-2725 2300);
FORCEADD OFFPAGE..1
(-3400 2300);
FORCEPROP 2 LAST $XR1 95 
J 0
(-3711 2300);
DISPLAY 0.638298 (-3711 2300);
PAINT MONO (-3711 2300);
FORCEPROP 2 LAST $XR0 21 
J 0
(-3621 2300);
DISPLAY 0.638298 (-3621 2300);
PAINT MONO (-3621 2300);
FORCEPROP 1 LAST OFFPAGE TRUE
J 0
(-3075 2175);
PAINT GREEN (-3075 2175);
DISPLAY INVISIBLE (-3075 2175);
FORCEPROP 1 LAST COMMENT_BODY TRUE
J 0
(-3275 2200);
DISPLAY 1.170213 (-3275 2200);
PAINT GREEN (-3275 2200);
DISPLAY INVISIBLE (-3275 2200);
FORCEPROP 2 LAST CDS_LIB mstr_standard
J 0
(-3400 2300);
PAINT ORANGE (-3400 2300);
DISPLAY INVISIBLE (-3400 2300);
FORCEPROP 2 LAST PATH I81
J 0
(-3650 2350);
DISPLAY 1.021277 (-3650 2350);
PAINT ORANGE (-3650 2350);
DISPLAY INVISIBLE (-3650 2350);
FORCEADD OFFPAGE..1
(-3400 2175);
FORCEPROP 2 LAST $XR1 95 
J 0
(-3711 2175);
DISPLAY 0.638298 (-3711 2175);
PAINT MONO (-3711 2175);
FORCEPROP 2 LAST $XR0 55 
J 0
(-3621 2175);
DISPLAY 0.638298 (-3621 2175);
PAINT MONO (-3621 2175);
FORCEPROP 1 LAST OFFPAGE TRUE
J 0
(-3075 2050);
PAINT GREEN (-3075 2050);
DISPLAY INVISIBLE (-3075 2050);
FORCEPROP 1 LAST COMMENT_BODY TRUE
J 0
(-3275 2075);
DISPLAY 1.170213 (-3275 2075);
PAINT GREEN (-3275 2075);
DISPLAY INVISIBLE (-3275 2075);
FORCEPROP 2 LAST CDS_LIB mstr_standard
J 0
(-3400 2175);
PAINT ORANGE (-3400 2175);
DISPLAY INVISIBLE (-3400 2175);
FORCEPROP 2 LAST PATH I83
J 0
(-3650 2225);
DISPLAY 1.021277 (-3650 2225);
PAINT ORANGE (-3650 2225);
DISPLAY INVISIBLE (-3650 2225);
FORCEADD RES..2
(-2025 4050);
FORCEPROP 1 LAST LOCATION R2T26
J 0
(-1980 4175);
DISPLAY 0.617021 (-1980 4175);
PAINT AQUA (-1980 4175);
FORCEPROP 1 LASTPIN (-2025 4150) $PN 1
J 0
(-2020 4112);
DISPLAY 0.617021 (-2020 4112);
PAINT ORANGE (-2020 4112);
FORCEPROP 1 LAST VALUE 200.0
J 0
(-1980 4125);
DISPLAY 0.617021 (-1980 4125);
PAINT SKYBLUE (-1980 4125);
FORCEPROP 1 LAST TOLERANCE 1%
J 0
(-1980 4075);
DISPLAY 0.617021 (-1980 4075);
PAINT SKYBLUE (-1980 4075);
FORCEPROP 1 LAST PACK_TYPE 0402
J 0
(-1885 3975);
DISPLAY 0.617021 (-1885 3975);
PAINT SKYBLUE (-1885 3975);
FORCEPROP 1 LAST PART_NUMBER G21796-004
J 0
(-1985 3925);
DISPLAY 0.617021 (-1985 3925);
PAINT BLUE (-1985 3925);
FORCEPROP 1 LAST WATTAGE 1/16W
J 0
(-1985 4025);
DISPLAY 0.617021 (-1985 4025);
PAINT SKYBLUE (-1985 4025);
FORCEPROP 1 LASTPIN (-2025 3950) $PN 2
J 0
(-2020 3960);
DISPLAY 0.617021 (-2020 3960);
PAINT ORANGE (-2020 3960);
FORCEPROP 1 LAST MATERIAL CHIP
J 0
(-1985 3975);
DISPLAY 0.617021 (-1985 3975);
PAINT SKYBLUE (-1985 3975);
FORCEPROP 1 LAST PATH I87
J 0
(-1975 4225);
DISPLAY 0.978723 (-1975 4225);
PAINT WHITE (-1975 4225);
DISPLAY INVISIBLE (-1975 4225);
FORCEPROP 2 LAST CDS_LOCATION R2T26
J 0
(-1980 4175);
DISPLAY 0.617021 (-1980 4175);
PAINT AQUA (-1980 4175);
DISPLAY INVISIBLE (-1980 4175);
FORCEPROP 2 LAST SEC 1
J 0
(-1975 4275);
DISPLAY 0.680851 (-1975 4275);
PAINT MONO (-1975 4275);
DISPLAY INVISIBLE (-1975 4275);
FORCEPROP 2 LAST SEC_TYPE 0402
J 0
(-1975 4275);
DISPLAY 1.021277 (-1975 4275);
PAINT ORANGE (-1975 4275);
DISPLAY INVISIBLE (-1975 4275);
FORCEPROP 2 LAST CDS_LIB mstr_discrete
J 0
(-2025 4050);
PAINT MONO (-2025 4050);
DISPLAY INVISIBLE (-2025 4050);
FORCEPROP 2 LAST BOM_COST PROC
J 0
(-2025 4050);
PAINT MONO (-2025 4050);
DISPLAY INVISIBLE (-2025 4050);
FORCEPROP 2 LAST ROOM PROC_SIDEBAND
J 0
(-2000 3825);
PAINT ORANGE (-2000 3825);
DISPLAY INVISIBLE (-2000 3825);
FORCEADD RES..2
(-1375 4125);
FORCEPROP 1 LAST WATTAGE 1/16W
J 0
(-1335 4100);
DISPLAY 0.617021 (-1335 4100);
PAINT SKYBLUE (-1335 4100);
FORCEPROP 1 LAST TOLERANCE 5%
J 0
(-1330 4150);
DISPLAY 0.617021 (-1330 4150);
PAINT SKYBLUE (-1330 4150);
FORCEPROP 1 LAST VALUE 0.0
J 0
(-1330 4200);
DISPLAY 0.617021 (-1330 4200);
PAINT SKYBLUE (-1330 4200);
FORCEPROP 1 LAST LOCATION R2T57
J 0
(-1330 4250);
DISPLAY 0.617021 (-1330 4250);
PAINT AQUA (-1330 4250);
FORCEPROP 1 LASTPIN (-1375 4225) $PN 1
J 0
(-1370 4187);
DISPLAY 0.617021 (-1370 4187);
PAINT ORANGE (-1370 4187);
FORCEPROP 1 LAST PACK_TYPE 0402
J 0
(-1335 3950);
DISPLAY 0.617021 (-1335 3950);
PAINT SKYBLUE (-1335 3950);
FORCEPROP 1 LAST PART_NUMBER G21497-005
J 0
(-1335 4000);
DISPLAY 0.617021 (-1335 4000);
PAINT BLUE (-1335 4000);
FORCEPROP 1 LAST MATERIAL EMPTY
J 0
(-1335 4050);
DISPLAY 0.617021 (-1335 4050);
PAINT RED (-1335 4050);
FORCEPROP 1 LASTPIN (-1375 4025) $PN 2
J 0
(-1370 4035);
DISPLAY 0.617021 (-1370 4035);
PAINT ORANGE (-1370 4035);
FORCEPROP 2 LAST SEC 1
J 0
(-1325 4350);
DISPLAY 0.680851 (-1325 4350);
PAINT MONO (-1325 4350);
DISPLAY INVISIBLE (-1325 4350);
FORCEPROP 2 LAST SEC_TYPE 0402
J 0
(-1325 4350);
DISPLAY 1.021277 (-1325 4350);
PAINT ORANGE (-1325 4350);
DISPLAY INVISIBLE (-1325 4350);
FORCEPROP 1 LAST PATH I88
J 0
(-1325 4300);
DISPLAY 0.978723 (-1325 4300);
PAINT WHITE (-1325 4300);
DISPLAY INVISIBLE (-1325 4300);
FORCEPROP 2 LAST CDS_LIB mstr_discrete
J 0
(-1375 4125);
PAINT ORANGE (-1375 4125);
DISPLAY INVISIBLE (-1375 4125);
FORCEADD RES..2
(-1100 4125);
FORCEPROP 1 LAST WATTAGE 1/16W
J 0
(-1060 4100);
DISPLAY 0.617021 (-1060 4100);
PAINT SKYBLUE (-1060 4100);
FORCEPROP 1 LAST TOLERANCE 5%
J 0
(-1055 4150);
DISPLAY 0.617021 (-1055 4150);
PAINT SKYBLUE (-1055 4150);
FORCEPROP 1 LAST VALUE 0.0
J 0
(-1055 4200);
DISPLAY 0.617021 (-1055 4200);
PAINT SKYBLUE (-1055 4200);
FORCEPROP 1 LAST LOCATION R2T61
J 0
(-1055 4250);
DISPLAY 0.617021 (-1055 4250);
PAINT AQUA (-1055 4250);
FORCEPROP 1 LASTPIN (-1100 4225) $PN 1
J 0
(-1095 4187);
DISPLAY 0.617021 (-1095 4187);
PAINT ORANGE (-1095 4187);
FORCEPROP 1 LAST PACK_TYPE 0402
J 0
(-1060 3950);
DISPLAY 0.617021 (-1060 3950);
PAINT SKYBLUE (-1060 3950);
FORCEPROP 1 LAST PART_NUMBER G21497-005
J 0
(-1060 4000);
DISPLAY 0.617021 (-1060 4000);
PAINT BLUE (-1060 4000);
FORCEPROP 1 LAST MATERIAL EMPTY
J 0
(-1060 4050);
DISPLAY 0.617021 (-1060 4050);
PAINT RED (-1060 4050);
FORCEPROP 1 LASTPIN (-1100 4025) $PN 2
J 0
(-1095 4035);
DISPLAY 0.617021 (-1095 4035);
PAINT ORANGE (-1095 4035);
FORCEPROP 2 LAST SEC 1
J 0
(-1050 4350);
DISPLAY 0.680851 (-1050 4350);
PAINT MONO (-1050 4350);
DISPLAY INVISIBLE (-1050 4350);
FORCEPROP 2 LAST SEC_TYPE 0402
J 0
(-1050 4350);
DISPLAY 1.021277 (-1050 4350);
PAINT ORANGE (-1050 4350);
DISPLAY INVISIBLE (-1050 4350);
FORCEPROP 1 LAST PATH I89
J 0
(-1050 4300);
DISPLAY 0.978723 (-1050 4300);
PAINT WHITE (-1050 4300);
DISPLAY INVISIBLE (-1050 4300);
FORCEPROP 2 LAST CDS_LIB mstr_discrete
J 0
(-1100 4125);
PAINT ORANGE (-1100 4125);
DISPLAY INVISIBLE (-1100 4125);
FORCEADD RES..2
(2025 3850);
FORCEPROP 1 LAST PACK_TYPE 0402
J 0
(2065 3675);
DISPLAY 0.617021 (2065 3675);
PAINT SKYBLUE (2065 3675);
FORCEPROP 1 LAST PART_NUMBER G21497-005
J 0
(2065 3725);
DISPLAY 0.617021 (2065 3725);
PAINT BLUE (2065 3725);
FORCEPROP 1 LAST MATERIAL EMPTY
J 0
(2065 3775);
DISPLAY 0.617021 (2065 3775);
PAINT RED (2065 3775);
FORCEPROP 1 LAST WATTAGE 1/16W
J 0
(2065 3825);
DISPLAY 0.617021 (2065 3825);
PAINT SKYBLUE (2065 3825);
FORCEPROP 1 LAST TOLERANCE 5%
J 0
(2070 3875);
DISPLAY 0.617021 (2070 3875);
PAINT SKYBLUE (2070 3875);
FORCEPROP 1 LAST VALUE 0.0
J 0
(2070 3925);
DISPLAY 0.617021 (2070 3925);
PAINT SKYBLUE (2070 3925);
FORCEPROP 1 LAST LOCATION R2T62
J 0
(2070 3975);
DISPLAY 0.617021 (2070 3975);
PAINT AQUA (2070 3975);
FORCEPROP 1 LASTPIN (2025 3950) $PN 1
J 0
(2030 3912);
DISPLAY 0.617021 (2030 3912);
PAINT ORANGE (2030 3912);
FORCEPROP 1 LASTPIN (2025 3750) $PN 2
J 0
(2030 3760);
DISPLAY 0.617021 (2030 3760);
PAINT ORANGE (2030 3760);
FORCEPROP 2 LAST SEC 1
J 0
(2075 4075);
DISPLAY 0.680851 (2075 4075);
PAINT MONO (2075 4075);
DISPLAY INVISIBLE (2075 4075);
FORCEPROP 2 LAST SEC_TYPE 0402
J 0
(2075 4075);
DISPLAY 1.021277 (2075 4075);
PAINT ORANGE (2075 4075);
DISPLAY INVISIBLE (2075 4075);
FORCEPROP 1 LAST PATH I93
J 0
(2075 4025);
DISPLAY 0.978723 (2075 4025);
PAINT WHITE (2075 4025);
DISPLAY INVISIBLE (2075 4025);
FORCEPROP 2 LAST CDS_LIB mstr_discrete
J 0
(2025 3850);
PAINT ORANGE (2025 3850);
DISPLAY INVISIBLE (2025 3850);
FORCEADD RES..2
(2400 3850);
FORCEPROP 1 LAST PACK_TYPE 0402
J 0
(2440 3675);
DISPLAY 0.617021 (2440 3675);
PAINT SKYBLUE (2440 3675);
FORCEPROP 1 LAST PART_NUMBER G21497-005
J 0
(2440 3725);
DISPLAY 0.617021 (2440 3725);
PAINT BLUE (2440 3725);
FORCEPROP 1 LAST WATTAGE 1/16W
J 0
(2440 3825);
DISPLAY 0.617021 (2440 3825);
PAINT SKYBLUE (2440 3825);
FORCEPROP 1 LAST LOCATION R2T58
J 0
(2445 3975);
DISPLAY 0.617021 (2445 3975);
PAINT AQUA (2445 3975);
FORCEPROP 1 LAST MATERIAL EMPTY
J 0
(2440 3775);
DISPLAY 0.617021 (2440 3775);
PAINT RED (2440 3775);
FORCEPROP 1 LAST VALUE 0.0
J 0
(2445 3925);
DISPLAY 0.617021 (2445 3925);
PAINT SKYBLUE (2445 3925);
FORCEPROP 1 LAST TOLERANCE 5%
J 0
(2445 3875);
DISPLAY 0.617021 (2445 3875);
PAINT SKYBLUE (2445 3875);
FORCEPROP 1 LASTPIN (2400 3950) $PN 1
J 0
(2405 3912);
DISPLAY 0.617021 (2405 3912);
PAINT ORANGE (2405 3912);
FORCEPROP 1 LASTPIN (2400 3750) $PN 2
J 0
(2405 3760);
DISPLAY 0.617021 (2405 3760);
PAINT ORANGE (2405 3760);
FORCEPROP 2 LAST SEC 1
J 0
(2450 4075);
DISPLAY 0.680851 (2450 4075);
PAINT MONO (2450 4075);
DISPLAY INVISIBLE (2450 4075);
FORCEPROP 2 LAST SEC_TYPE 0402
J 0
(2450 4075);
DISPLAY 1.021277 (2450 4075);
PAINT ORANGE (2450 4075);
DISPLAY INVISIBLE (2450 4075);
FORCEPROP 1 LAST PATH I94
J 0
(2450 4025);
DISPLAY 0.978723 (2450 4025);
PAINT WHITE (2450 4025);
DISPLAY INVISIBLE (2450 4025);
FORCEPROP 2 LAST CDS_LIB mstr_discrete
J 0
(2400 3850);
PAINT ORANGE (2400 3850);
DISPLAY INVISIBLE (2400 3850);
FORCEADD CAP_A..1
(1950 600);
FORCEPROP 1 LAST TOLERANCE 10%
J 0
(2000 550);
DISPLAY 0.617021 (2000 550);
PAINT SKYBLUE (2000 550);
FORCEPROP 1 LAST VOLTAGE 16V
J 0
(2000 600);
DISPLAY 0.617021 (2000 600);
PAINT SKYBLUE (2000 600);
FORCEPROP 1 LAST VALUE 0.1UF
J 0
(2000 650);
DISPLAY 0.617021 (2000 650);
PAINT SKYBLUE (2000 650);
FORCEPROP 1 LASTPIN (1950 500) $PN 2
J 0
(1960 480);
DISPLAY 0.617021 (1960 480);
PAINT MONO (1960 480);
FORCEPROP 1 LAST PART_NUMBER A36096-030
J 0
(2000 450);
DISPLAY 0.617021 (2000 450);
PAINT BLUE (2000 450);
FORCEPROP 1 LAST PACK_TYPE 0402V
J 0
(2000 400);
DISPLAY 0.617021 (2000 400);
PAINT SKYBLUE (2000 400);
FORCEPROP 1 LAST MATERIAL X7R
J 0
(2000 500);
DISPLAY 0.617021 (2000 500);
PAINT SKYBLUE (2000 500);
FORCEPROP 1 LASTPIN (1950 700) $PN 1
J 0
(1960 680);
DISPLAY 0.617021 (1960 680);
PAINT MONO (1960 680);
FORCEPROP 1 LAST LOCATION C2T32
J 0
(2000 700);
DISPLAY 0.617021 (2000 700);
PAINT AQUA (2000 700);
FORCEPROP 2 LAST ROOM PROC_SIDEBAND
J 0
(2000 350);
DISPLAY 0.978723 (2000 350);
PAINT ORANGE (2000 350);
DISPLAY INVISIBLE (2000 350);
FORCEPROP 2 LAST CDS_LIB dev_discrete
J 0
(1950 600);
PAINT ORANGE (1950 600);
DISPLAY INVISIBLE (1950 600);
FORCEPROP 2 LAST BOM_COST PROC
J 0
(1950 600);
PAINT MONO (1950 600);
DISPLAY INVISIBLE (1950 600);
FORCEPROP 2 LAST CDS_LOCATION C2T32
J 0
(2000 700);
DISPLAY 0.617021 (2000 700);
PAINT AQUA (2000 700);
DISPLAY INVISIBLE (2000 700);
FORCEPROP 2 LAST SEC 1
J 0
(2000 800);
DISPLAY 0.936170 (2000 800);
PAINT MONO (2000 800);
DISPLAY INVISIBLE (2000 800);
FORCEPROP 2 LAST SEC_TYPE 0402V
J 0
(2000 800);
PAINT MONO (2000 800);
DISPLAY INVISIBLE (2000 800);
FORCEPROP 2 LAST CDS_SEC 1
J 0
(2000 750);
PAINT ORANGE (2000 750);
DISPLAY INVISIBLE (2000 750);
FORCEPROP 1 LAST PATH I95
J 0
(2000 750);
DISPLAY 0.978723 (2000 750);
PAINT WHITE (2000 750);
DISPLAY INVISIBLE (2000 750);
FORCEADD RES..2
(2300 600);
FORCEPROP 1 LAST PART_NUMBER G21796-017
J 0
(2340 450);
DISPLAY 0.617021 (2340 450);
PAINT BLUE (2340 450);
FORCEPROP 1 LAST PACK_TYPE 0402
J 0
(2340 400);
DISPLAY 0.617021 (2340 400);
PAINT SKYBLUE (2340 400);
FORCEPROP 1 LAST MATERIAL CHIP
J 0
(2340 500);
DISPLAY 0.617021 (2340 500);
PAINT SKYBLUE (2340 500);
FORCEPROP 1 LAST WATTAGE 1/16W
J 0
(2340 550);
DISPLAY 0.617021 (2340 550);
PAINT SKYBLUE (2340 550);
FORCEPROP 1 LAST TOLERANCE 1%
J 0
(2345 600);
DISPLAY 0.617021 (2345 600);
PAINT SKYBLUE (2345 600);
FORCEPROP 1 LAST VALUE 100.0
J 0
(2345 650);
DISPLAY 0.617021 (2345 650);
PAINT SKYBLUE (2345 650);
FORCEPROP 1 LAST LOCATION R2T39
J 0
(2345 700);
DISPLAY 0.617021 (2345 700);
PAINT AQUA (2345 700);
FORCEPROP 1 LASTPIN (2300 500) $PN 2
J 0
(2305 510);
DISPLAY 0.617021 (2305 510);
PAINT MONO (2305 510);
FORCEPROP 1 LASTPIN (2300 700) $PN 1
J 0
(2305 662);
DISPLAY 0.617021 (2305 662);
PAINT MONO (2305 662);
FORCEPROP 2 LAST CDS_LIB mstr_discrete
J 2
(2300 600);
PAINT ORANGE (2300 600);
DISPLAY INVISIBLE (2300 600);
FORCEPROP 2 LAST BOM_COST PROC
J 0
(2300 600);
PAINT MONO (2300 600);
DISPLAY INVISIBLE (2300 600);
FORCEPROP 2 LAST CDS_LOCATION R2T39
J 0
(2345 725);
DISPLAY 0.617021 (2345 725);
PAINT AQUA (2345 725);
DISPLAY INVISIBLE (2345 725);
FORCEPROP 1 LAST PATH I98
J 0
(2350 775);
DISPLAY 0.978723 (2350 775);
PAINT WHITE (2350 775);
DISPLAY INVISIBLE (2350 775);
FORCEPROP 2 LAST SEC_TYPE 0402
J 0
(2350 825);
DISPLAY 1.021277 (2350 825);
PAINT ORANGE (2350 825);
DISPLAY INVISIBLE (2350 825);
FORCEPROP 2 LAST SEC 1
J 0
(2350 825);
DISPLAY 0.680851 (2350 825);
PAINT MONO (2350 825);
DISPLAY INVISIBLE (2350 825);
FORCEPROP 2 LAST ROOM PROC_SIDEBAND
J 2
(2600 375);
DISPLAY 0.978723 (2600 375);
PAINT ORANGE (2600 375);
DISPLAY INVISIBLE (2600 375);
FORCEADD GND..1
(2300 250);
FORCEPROP 3 LASTPIN (2300 300) SIG_NAME GND\g
J 0
(2310 310);
DISPLAY 0.659574 (2310 310);
PAINT MONO (2310 310);
DISPLAY INVISIBLE (2310 310);
FORCEPROP 1 LAST BODY_TYPE PLUMBING
J 0
(2255 207);
DISPLAY 0.340426 (2255 207);
PAINT GREEN (2255 207);
DISPLAY INVISIBLE (2255 207);
FORCEPROP 1 LAST VOLTAGE 0
J 0
(2300 250);
PAINT SKYBLUE (2300 250);
DISPLAY INVISIBLE (2300 250);
FORCEPROP 2 LAST CDS_LIB mstr_symbols
J 0
(2300 250);
PAINT ORANGE (2300 250);
DISPLAY INVISIBLE (2300 250);
FORCEPROP 1 LAST HDL_POWER GND
J 0
(2300 400);
DISPLAY 1.212766 (2300 400);
PAINT GREEN (2300 400);
DISPLAY INVISIBLE (2300 400);
FORCEPROP 1 LAST PATH I99
J 0
(2375 250);
DISPLAY 0.872340 (2375 250);
PAINT AQUA (2375 250);
DISPLAY INVISIBLE (2375 250);
FORCEPROP 1 LAST SIZE 1B
J 0
(2375 200);
DISPLAY 1.212766 (2375 200);
PAINT GREEN (2375 200);
DISPLAY INVISIBLE (2375 200);
FORCEADD CAD_NOTE..1
(-2775 4550);
FORCEPROP 0 LAST L1 PLACE ALL COMPONENTS NEAR GTL CONVERTER
J 0
(-2925 4450);
DISPLAY 0.808511 (-2925 4450);
PAINT ORANGE (-2925 4450);
FORCEPROP 1 LAST COMMENT_BODY TRUE
J 0
(-2750 4650);
DISPLAY 1.319149 (-2750 4650);
PAINT WHITE (-2750 4650);
DISPLAY INVISIBLE (-2750 4650);
FORCEPROP 2 LAST CDS_LIB mstr_symbols
J 0
(-2775 4550);
PAINT WHITE (-2775 4550);
DISPLAY INVISIBLE (-2775 4550);
FORCEPROP 2 LAST BOM_COST SM_CONTROLLER
J 0
(-2925 4500);
PAINT WHITE (-2925 4500);
DISPLAY INVISIBLE (-2925 4500);
FORCEPROP 2 LAST ROOM BMC
J 0
(-2925 4500);
PAINT WHITE (-2925 4500);
DISPLAY INVISIBLE (-2925 4500);
FORCEADD DNS..2
(-1095 1895);
PAINT RED (-1095 1895);
FORCEPROP 2 LAST CDS_LIB mstr_misc
J 0
(-1095 1895);
PAINT ORANGE (-1095 1895);
DISPLAY INVISIBLE (-1095 1895);
FORCEPROP 1 LAST COMMENT_BODY TRUE
R 1
J 0
(-1020 1670);
DISPLAY 0.872340 (-1020 1670);
PAINT GREEN (-1020 1670);
DISPLAY INVISIBLE (-1020 1670);
FORCEADD DNS..2
(-2220 70);
PAINT RED (-2220 70);
FORCEPROP 2 LAST CDS_LIB mstr_misc
J 0
(-2220 70);
PAINT ORANGE (-2220 70);
DISPLAY INVISIBLE (-2220 70);
FORCEPROP 1 LAST COMMENT_BODY TRUE
R 1
J 0
(-2145 -155);
DISPLAY 0.872340 (-2145 -155);
PAINT GREEN (-2145 -155);
DISPLAY INVISIBLE (-2145 -155);
FORCEADD DNS..2
(2405 3845);
PAINT RED (2405 3845);
FORCEPROP 2 LAST CDS_LIB mstr_misc
J 0
(2405 3845);
PAINT ORANGE (2405 3845);
DISPLAY INVISIBLE (2405 3845);
FORCEPROP 1 LAST COMMENT_BODY TRUE
R 1
J 0
(2480 3620);
DISPLAY 0.872340 (2480 3620);
PAINT GREEN (2480 3620);
DISPLAY INVISIBLE (2480 3620);
FORCEADD CAD_NOTE..1
(-325 2350);
FORCEPROP 0 LAST L2 FOR RESISTORS
J 0
(-475 2200);
DISPLAY 0.638298 (-475 2200);
PAINT ORANGE (-475 2200);
FORCEPROP 0 LAST L1 USE SHARED PADS
J 0
(-475 2250);
DISPLAY 0.617021 (-475 2250);
PAINT WHITE (-475 2250);
FORCEPROP 1 LAST COMMENT_BODY TRUE
J 0
(-300 2450);
DISPLAY 1.319149 (-300 2450);
PAINT WHITE (-300 2450);
DISPLAY INVISIBLE (-300 2450);
FORCEPROP 2 LAST CDS_LIB mstr_symbols
J 0
(-325 2350);
PAINT ORANGE (-325 2350);
DISPLAY INVISIBLE (-325 2350);
FORCEADD DESIGN_NOTE..1
(-200 1550);
FORCEPROP 2 LAST CDS_LIB mstr_symbols
J 0
(-200 1550);
PAINT ORANGE (-200 1550);
DISPLAY INVISIBLE (-200 1550);
FORCEPROP 1 LAST COMMENT_BODY TRUE
J 0
(-175 1650);
DISPLAY 0.978723 (-175 1650);
PAINT ORANGE (-175 1650);
DISPLAY INVISIBLE (-175 1650);
FORCEADD DNS..2
(-2220 845);
PAINT RED (-2220 845);
FORCEPROP 2 LAST CDS_LIB mstr_misc
J 0
(-2220 845);
PAINT ORANGE (-2220 845);
DISPLAY INVISIBLE (-2220 845);
FORCEPROP 1 LAST COMMENT_BODY TRUE
R 1
J 0
(-2145 620);
DISPLAY 0.872340 (-2145 620);
PAINT GREEN (-2145 620);
DISPLAY INVISIBLE (-2145 620);
FORCEADD DNS..2
(-1370 4120);
PAINT RED (-1370 4120);
FORCEPROP 2 LAST CDS_LIB mstr_misc
J 0
(-1370 4120);
PAINT ORANGE (-1370 4120);
DISPLAY INVISIBLE (-1370 4120);
FORCEPROP 1 LAST COMMENT_BODY TRUE
R 1
J 0
(-1295 3895);
DISPLAY 0.872340 (-1295 3895);
PAINT GREEN (-1295 3895);
DISPLAY INVISIBLE (-1295 3895);
FORCEADD DNS..2
(2405 2220);
PAINT RED (2405 2220);
FORCEPROP 2 LAST CDS_LIB mstr_misc
J 0
(2405 2220);
PAINT ORANGE (2405 2220);
DISPLAY INVISIBLE (2405 2220);
FORCEPROP 1 LAST COMMENT_BODY TRUE
R 1
J 0
(2480 1995);
DISPLAY 0.872340 (2480 1995);
PAINT GREEN (2480 1995);
DISPLAY INVISIBLE (2480 1995);
FORCEADD DNS..2
(-1095 4120);
PAINT RED (-1095 4120);
FORCEPROP 2 LAST CDS_LIB mstr_misc
J 0
(-1095 4120);
PAINT ORANGE (-1095 4120);
DISPLAY INVISIBLE (-1095 4120);
FORCEPROP 1 LAST COMMENT_BODY TRUE
R 1
J 0
(-1020 3895);
DISPLAY 0.872340 (-1020 3895);
PAINT GREEN (-1020 3895);
DISPLAY INVISIBLE (-1020 3895);
FORCEADD DNS..2
(1755 1095);
PAINT RED (1755 1095);
FORCEPROP 2 LAST CDS_LIB mstr_misc
J 0
(1755 1095);
PAINT ORANGE (1755 1095);
DISPLAY INVISIBLE (1755 1095);
FORCEPROP 1 LAST COMMENT_BODY TRUE
R 1
J 0
(1830 870);
DISPLAY 0.872340 (1830 870);
PAINT GREEN (1830 870);
DISPLAY INVISIBLE (1830 870);
FORCEADD CAD_NOTE..1
(-1775 -50);
FORCEPROP 0 LAST L1 USE SHARED PADS WITH
J 0
(-1925 -150);
DISPLAY 0.617021 (-1925 -150);
PAINT WHITE (-1925 -150);
FORCEPROP 0 LAST L2 33.2OHM RESISTORS
J 0
(-1925 -200);
DISPLAY 0.638298 (-1925 -200);
PAINT ORANGE (-1925 -200);
FORCEPROP 1 LAST COMMENT_BODY TRUE
J 0
(-1750 50);
DISPLAY 1.319149 (-1750 50);
PAINT WHITE (-1750 50);
DISPLAY INVISIBLE (-1750 50);
FORCEPROP 2 LAST CDS_LIB mstr_symbols
J 0
(-1775 -50);
PAINT ORANGE (-1775 -50);
DISPLAY INVISIBLE (-1775 -50);
FORCEADD DNS..2
(2030 3845);
PAINT RED (2030 3845);
FORCEPROP 2 LAST CDS_LIB mstr_misc
J 0
(2030 3845);
PAINT ORANGE (2030 3845);
DISPLAY INVISIBLE (2030 3845);
FORCEPROP 1 LAST COMMENT_BODY TRUE
R 1
J 0
(2105 3620);
DISPLAY 0.872340 (2105 3620);
PAINT GREEN (2105 3620);
DISPLAY INVISIBLE (2105 3620);
FORCEADD DNS..2
(-2220 1245);
PAINT RED (-2220 1245);
FORCEPROP 2 LAST CDS_LIB mstr_misc
J 0
(-2220 1245);
PAINT ORANGE (-2220 1245);
DISPLAY INVISIBLE (-2220 1245);
FORCEPROP 1 LAST COMMENT_BODY TRUE
R 1
J 0
(-2145 1020);
DISPLAY 0.872340 (-2145 1020);
PAINT GREEN (-2145 1020);
DISPLAY INVISIBLE (-2145 1020);
FORCEADD CAD_NOTE..1
(-2625 2000);
FORCEPROP 0 LAST L2 THE OTHER NEAR GTL2014 FOR EACH SIGNAL
J 0
(-2775 1825);
DISPLAY 0.808511 (-2775 1825);
PAINT ORANGE (-2775 1825);
FORCEPROP 0 LAST L1 PLACE ONE 150 OHM PU RESISTOR NEAR CPU
J 0
(-2775 1900);
DISPLAY 0.808511 (-2775 1900);
PAINT ORANGE (-2775 1900);
FORCEPROP 1 LAST COMMENT_BODY TRUE
J 0
(-2600 2100);
DISPLAY 1.319149 (-2600 2100);
PAINT WHITE (-2600 2100);
DISPLAY INVISIBLE (-2600 2100);
FORCEPROP 2 LAST CDS_LIB mstr_symbols
J 0
(-2625 2000);
PAINT WHITE (-2625 2000);
DISPLAY INVISIBLE (-2625 2000);
FORCEADD CAD_NOTE..1
(2900 2350);
FORCEPROP 0 LAST L1 USE SHARED PADS WITH 0OHM
J 0
(2750 2250);
DISPLAY 0.617021 (2750 2250);
PAINT WHITE (2750 2250);
FORCEPROP 0 LAST L2 STEERING RESISTORS
J 0
(2750 2200);
DISPLAY 0.638298 (2750 2200);
PAINT ORANGE (2750 2200);
FORCEPROP 1 LAST COMMENT_BODY TRUE
J 0
(2925 2450);
DISPLAY 1.319149 (2925 2450);
PAINT WHITE (2925 2450);
DISPLAY INVISIBLE (2925 2450);
FORCEPROP 2 LAST CDS_LIB mstr_symbols
J 0
(2900 2350);
PAINT ORANGE (2900 2350);
DISPLAY INVISIBLE (2900 2350);
FORCEADD DNS..2
(-2220 470);
PAINT RED (-2220 470);
FORCEPROP 2 LAST CDS_LIB mstr_misc
J 0
(-2220 470);
PAINT ORANGE (-2220 470);
DISPLAY INVISIBLE (-2220 470);
FORCEPROP 1 LAST COMMENT_BODY TRUE
R 1
J 0
(-2145 245);
DISPLAY 0.872340 (-2145 245);
PAINT GREEN (-2145 245);
DISPLAY INVISIBLE (-2145 245);
FORCEADD CAD_NOTE..1
(1175 2275);
FORCEPROP 0 LAST L2 STEERING RESISTORS
J 0
(1025 2125);
DISPLAY 0.638298 (1025 2125);
PAINT ORANGE (1025 2125);
FORCEPROP 0 LAST L1 USE SHARED PADS FOR 0OHM
J 0
(1025 2175);
DISPLAY 0.617021 (1025 2175);
PAINT WHITE (1025 2175);
FORCEPROP 1 LAST COMMENT_BODY TRUE
J 0
(1200 2375);
DISPLAY 1.319149 (1200 2375);
PAINT WHITE (1200 2375);
DISPLAY INVISIBLE (1200 2375);
FORCEPROP 2 LAST CDS_LIB mstr_symbols
J 0
(1175 2275);
PAINT ORANGE (1175 2275);
DISPLAY INVISIBLE (1175 2275);
FORCEADD INTEL_CORP_BPAGE..1
(4200 -325);
FORCEPROP 1 LAST CDS_CON_LAST_MODIFIED Fri Jun 16 17:48:34 2017
J 0
(2775 0);
PAINT ORANGE (2775 0);
DISPLAY INVISIBLE (2775 0);
FORCEPROP 1 LAST CUSTOM_TXT_CDS <CURRENT_DESIGN_SHEET> OF <TOTAL_DESIGN_SHEETS>
J 0
(3700 -300);
PAINT ORANGE (3700 -300);
FORCEPROP 1 LAST CUSTOM_TXT_CDS <CON_LAST_MODIFIED>
J 0
(200 -225);
PAINT ORANGE (200 -225);
FORCEPROP 2 LAST CUSTOM_TXT_CDS <XR_PAGE_TITLE>
J 0
(-3690 4925);
DISPLAY 0.638298 (-3690 4925);
PAINT PINK (-3690 4925);
DISPLAY INVISIBLE (-3690 4925);
FORCEPROP 1 LAST SCH_TITLE ERRORS CIRCUITRY
J 0
(-3750 -275);
DISPLAY 1.212766 (-3750 -275);
PAINT ORANGE (-3750 -275);
FORCEPROP 1 LAST COMMENT_BODY TRUE
J 0
(4212 -313);
DISPLAY 0.468085 (4212 -313);
PAINT GREEN (4212 -313);
DISPLAY INVISIBLE (4212 -313);
FORCEPROP 2 LAST CDS_LIB mstr_symbols
J 0
(4200 -325);
PAINT MONO (4200 -325);
DISPLAY INVISIBLE (4200 -325);
FORCEPROP 2 LAST PAGE_BORDER TRUE
J 0
(-3690 4925);
DISPLAY 0.638298 (-3690 4925);
PAINT PINK (-3690 4925);
DISPLAY INVISIBLE (-3690 4925);
FORCEPROP 2 LAST CDS_XR_PAGE_TITLE CR-93 : @BASEBOARD_FAB2_LIB.BASEBOARD_FAB2(SCH_1):PAGE93
J 0
(-3690 4925);
DISPLAY 0.638298 (-3690 4925);
PAINT PINK (-3690 4925);
DISPLAY INVISIBLE (-3690 4925);
FORCEADD DNS..2
(2030 2220);
PAINT RED (2030 2220);
FORCEPROP 2 LAST CDS_LIB mstr_misc
J 0
(2030 2220);
PAINT ORANGE (2030 2220);
DISPLAY INVISIBLE (2030 2220);
FORCEPROP 1 LAST COMMENT_BODY TRUE
R 1
J 0
(2105 1995);
DISPLAY 0.872340 (2105 1995);
PAINT GREEN (2105 1995);
DISPLAY INVISIBLE (2105 1995);
FORCEADD DNS..2
(-1395 1895);
PAINT RED (-1395 1895);
FORCEPROP 2 LAST CDS_LIB mstr_misc
J 0
(-1395 1895);
PAINT ORANGE (-1395 1895);
DISPLAY INVISIBLE (-1395 1895);
FORCEPROP 1 LAST COMMENT_BODY TRUE
R 1
J 0
(-1320 1670);
DISPLAY 0.872340 (-1320 1670);
PAINT GREEN (-1320 1670);
DISPLAY INVISIBLE (-1320 1670);
FORCEADD DESIGN_NOTE..1
(225 2800);
PAINT PURPLE (225 2800);
FORCEPROP 0 LAST L2 THE PINS 'BX' ARE INPUTS & 'AX' OUTPUTS ARE PUSH-PULL.
J 0
(25 2625);
DISPLAY 0.808511 (25 2625);
PAINT VIOLET (25 2625);
FORCEPROP 0 LAST L3 VREF IS SET AT 2/3 OF VCCIO
J 0
(25 2575);
DISPLAY 0.808511 (25 2575);
PAINT VIOLET (25 2575);
FORCEPROP 0 LAST L1 THE GTL2014 IS BEING USED AS GTL TO LVTTL CONVERTER, SO
J 0
(25 2675);
DISPLAY 0.808511 (25 2675);
PAINT VIOLET (25 2675);
FORCEPROP 2 LAST ROOM PVCCIN_CPU1_DECAP_VR
J 0
(25 2750);
PAINT MONO (25 2750);
DISPLAY INVISIBLE (25 2750);
FORCEPROP 1 LAST COMMENT_BODY TRUE
J 0
(250 2900);
DISPLAY 1.319149 (250 2900);
PAINT GREEN (250 2900);
DISPLAY INVISIBLE (250 2900);
FORCEPROP 2 LAST BOM_COST SM_CONTROLLER
J 0
(25 2750);
PAINT MONO (25 2750);
DISPLAY INVISIBLE (25 2750);
FORCEPROP 2 LAST CDS_LIB mstr_symbols
J 0
(225 2800);
PAINT ORANGE (225 2800);
DISPLAY INVISIBLE (225 2800);
WIRE 16 -1 (-2200 2700)(-2200 2750);
WIRE 16 -1 (-1900 2700)(-2200 2700);
WIRE 16 -1 (-2200 2600)(-2200 2700);
WIRE 16 -1 (-1900 2700)(-1900 2600);
WIRE 16 -1 (3700 275)(3700 325);
WIRE 16 -1 (2300 1200)(2300 1250);
WIRE 16 -1 (1750 1250)(1750 1200);
WIRE 16 -1 (-200 2875)(-200 2950);
WIRE 16 -1 (-200 2950)(-200 3000);
WIRE 16 -1 (-25 2950)(-200 2950);
WIRE 16 -1 (-200 3000)(-200 3050);
WIRE 16 -1 (-25 3000)(-200 3000);
WIRE 16 -1 (-200 3050)(-25 3050);
WIRE 16 -1 (-2325 4225)(-2325 4250);
WIRE 16 -1 (-2325 4225)(-2025 4225);
WIRE 16 -1 (-2325 4150)(-2325 4225);
WIRE 16 -1 (-2025 4225)(-2025 4150);
WIRE 16 -1 (1000 4050)(1000 4100);
WIRE 16 -1 (1000 3650)(1000 4050);
WIRE 16 -1 (1150 4050)(1000 4050);
WIRE 16 -1 (1150 3975)(1150 4050);
WIRE 16 -1 (875 3650)(1000 3650);
WIRE 16 -1 (1150 3725)(1150 3775);
WIRE 16 -1 (-2750 2750)(-2750 2725);
WIRE 16 -1 (-2475 2725)(-2750 2725);
WIRE 16 -1 (-2750 2725)(-2750 2625);
WIRE 16 -1 (-2475 2625)(-2475 2725);
WIRE 16 -1 (2300 350)(2300 300);
WIRE 16 -1 (1950 350)(2300 350);
WIRE 16 -1 (2300 500)(2300 350);
WIRE 16 -1 (1950 500)(1950 350);
WIRE 16 -1 (-2475 3200)(-2650 3200);
WIRE 16 -1 (-2475 3425)(-2650 3425);
WIRE 16 -1 (-1025 3300)(-1100 3300);
WIRE 16 -1 (-1100 4025)(-1100 3300);
WIRE 16 -1 (-2025 3950)(-2025 3300);
WIRE 16 -1 (-2025 3300)(-1100 3300);
WIRE 16 -1 (-2475 3300)(-2475 3425);
WIRE 16 -1 (-2475 3300)(-2475 3200);
WIRE 16 -1 (-2475 3300)(-2025 3300);
FORCEPROP 0 LAST SIG_NAME H_CPU_ERR1_GTL_R_N
J 0
(-2275 3310);
DISPLAY 0.617021 (-2275 3310);
PAINT ORANGE (-2275 3310);
FORCEPROP 2 LASTPROP $XRERR UNIQUE?
J 0
(-2515 3310);
DISPLAY 0.638298 (-2515 3310);
PAINT MONO (-2515 3310);
DISPLAY INVISIBLE (-2515 3310);
WIRE 16 2175 (-2975 3000)(-1700 3000);
WIRE 16 2175 (-1700 3000)(-1700 4425);
WIRE 16 2175 (-2975 4425)(-2975 3000);
WIRE 16 2175 (-2975 4425)(-1700 4425);
WIRE 3 682 (2150 900)(2600 900);
WIRE 3 682 (2150 1400)(2150 900);
WIRE 3 682 (2600 900)(2600 1400);
WIRE 3 682 (2600 1400)(2150 1400);
WIRE 16 2175 (-2900 2075)(-1625 2075);
WIRE 16 2175 (-1625 2075)(-1625 2925);
WIRE 16 2175 (-2900 2925)(-2900 2075);
WIRE 16 2175 (-2900 2925)(-1625 2925);
WIRE 16 -1 (-1400 1650)(-1400 1800);
WIRE 16 -1 (2400 1650)(-1400 1650);
FORCEPROP 2 LAST SIG_NAME H_CPU1_PROCHOT_G_PCH_N
J 0
(25 1660);
DISPLAY 0.617021 (25 1660);
PAINT ORANGE (25 1660);
FORCEPROP 2 LASTPROP $XRERR UNIQUE?
J 0
(-215 1660);
DISPLAY 0.638298 (-215 1660);
PAINT MONO (-215 1660);
DISPLAY INVISIBLE (-215 1660);
WIRE 16 -1 (2400 2125)(2400 1650);
WIRE 16 -1 (-3350 3975)(-2850 3975);
FORCEPROP 2 LAST SIG_NAME H_CPU0_ERR0_G_N
J 0
(-3325 3985);
DISPLAY 0.617021 (-3325 3985);
PAINT ORANGE (-3325 3985);
WIRE 16 -1 (-450 300)(-100 300);
WIRE 16 -1 (1150 300)(-100 300);
WIRE 16 -1 (-450 300)(-450 1300);
WIRE 16 -1 (-450 1300)(-450 1400);
WIRE 16 -1 (-100 1400)(-100 300);
WIRE 16 -1 (-450 1400)(-100 1400);
WIRE 16 -1 (1150 1400)(-100 1400);
WIRE 16 -1 (-450 1300)(1150 1300);
WIRE 16 -1 (1150 300)(1150 1300);
WIRE 16 -1 (1150 1300)(1150 1400);
WIRE 16 -1 (1750 1000)(1750 850);
WIRE 16 -1 (1750 850)(2300 850);
WIRE 16 -1 (2300 950)(2300 850);
WIRE 16 -1 (2300 800)(2300 700);
WIRE 16 -1 (2300 850)(2300 800);
WIRE 16 -1 (1950 700)(1950 800);
WIRE 16 -1 (1950 800)(2300 800);
FORCEPROP 0 LAST VOLTAGE 0.734
J 0
(2100 850);
DISPLAY 1.021277 (2100 850);
PAINT SKYBLUE (2100 850);
DISPLAY INVISIBLE (2100 850);
WIRE 16 -1 (1650 800)(1950 800);
FORCEPROP 2 LAST SIG_NAME P0V7_GTL2104_5_VREF
J 0
(1665 810);
DISPLAY 0.617021 (1665 810);
PAINT ORANGE (1665 810);
WIRE 16 -1 (3700 525)(3700 650);
WIRE 16 -1 (3275 650)(3700 650);
FORCEPROP 2 LAST SIG_NAME PD_GTL2104_4_DIR
J 0
(3300 660);
DISPLAY 0.617021 (3300 660);
PAINT ORANGE (3300 660);
WIRE 16 2175 (2700 2425)(2700 3475);
WIRE 16 2175 (3100 2425)(2700 2425);
WIRE 16 2175 (2700 3475)(3100 3475);
WIRE 16 2175 (3100 3475)(3100 2425);
WIRE 16 -1 (1975 3100)(2025 3100);
WIRE 16 -1 (2025 3750)(2025 3100);
WIRE 16 -1 (2850 3100)(2025 3100);
FORCEPROP 2 LAST SIG_NAME FM_CPU_ERR1_LVT3_K_N
J 0
(2090 3110);
DISPLAY 0.617021 (2090 3110);
PAINT ORANGE (2090 3110);
FORCEPROP 2 LASTPROP $XRERR UNIQUE?
J 0
(1850 3110);
DISPLAY 0.638298 (1850 3110);
PAINT MONO (1850 3110);
DISPLAY INVISIBLE (1850 3110);
WIRE 16 -1 (2025 2125)(2025 1700);
WIRE 16 -1 (-1100 1800)(-1100 1700);
WIRE 16 -1 (-1100 1700)(2025 1700);
FORCEPROP 2 LAST SIG_NAME H_CPU0_PROCHOT_G_PCH_N
J 0
(25 1710);
DISPLAY 0.617021 (25 1710);
PAINT ORANGE (25 1710);
FORCEPROP 2 LASTPROP $XRERR UNIQUE?
J 0
(-215 1710);
DISPLAY 0.638298 (-215 1710);
PAINT MONO (-215 1710);
DISPLAY INVISIBLE (-215 1710);
WIRE 16 -1 (2025 2325)(2025 2850);
WIRE 16 -1 (1975 2850)(2025 2850);
WIRE 16 -1 (2850 2850)(2025 2850);
FORCEPROP 2 LAST SIG_NAME FM_CPU0_PROCHOT_LVT3_K_N
J 0
(2090 2860);
DISPLAY 0.617021 (2090 2860);
PAINT ORANGE (2090 2860);
FORCEPROP 2 LASTPROP $XRERR UNIQUE?
J 0
(1850 2860);
DISPLAY 0.638298 (1850 2860);
PAINT MONO (1850 2860);
DISPLAY INVISIBLE (1850 2860);
WIRE 16 -1 (875 3600)(1425 3600);
FORCEPROP 0 LAST SIG_NAME P0V7_GTL2104_5_VREF
J 0
(975 3610);
DISPLAY 0.617021 (975 3610);
PAINT ORANGE (975 3610);
WIRE 16 -1 (875 3500)(1425 3500);
FORCEPROP 2 LAST SIG_NAME PD_GTL2104_4_DIR
J 0
(975 3510);
DISPLAY 0.617021 (975 3510);
PAINT ORANGE (975 3510);
WIRE 16 -1 (875 3350)(1775 3350);
FORCEPROP 2 LAST SIG_NAME FM_CPU_ERR0_LVT3_R_N
J 0
(1000 3360);
DISPLAY 0.617021 (1000 3360);
PAINT ORANGE (1000 3360);
FORCEPROP 2 LASTPROP $XRERR UNIQUE?
J 0
(760 3360);
DISPLAY 0.638298 (760 3360);
PAINT MONO (760 3360);
DISPLAY INVISIBLE (760 3360);
WIRE 16 -1 (1625 2575)(1775 2575);
WIRE 16 -1 (1625 3200)(1625 2575);
WIRE 16 -1 (875 3200)(1625 3200);
FORCEPROP 2 LAST SIG_NAME FM_CPU1_PROCHOT_LVT3_R_N
J 0
(1000 3210);
DISPLAY 0.617021 (1000 3210);
PAINT ORANGE (1000 3210);
FORCEPROP 2 LASTPROP $XRERR UNIQUE?
J 0
(760 3210);
DISPLAY 0.638298 (760 3210);
PAINT MONO (760 3210);
DISPLAY INVISIBLE (760 3210);
WIRE 16 2175 (1600 4075)(1600 2000);
WIRE 16 2175 (2600 4075)(1600 4075);
WIRE 16 2175 (1600 2000)(2600 2000);
WIRE 16 2175 (2600 2000)(2600 4075);
WIRE 16 -1 (-2125 675)(-1375 675);
FORCEPROP 2 LAST SIG_NAME FM_CPU0_PROCHOT_LVT3_BMC_N
J 0
(-1975 685);
DISPLAY 0.617021 (-1975 685);
PAINT ORANGE (-1975 685);
WIRE 16 2175 (-1525 1750)(-550 1750);
WIRE 16 2175 (-1525 4350)(-1525 1750);
WIRE 16 2175 (-550 1750)(-550 4350);
WIRE 16 2175 (-550 4350)(-1525 4350);
WIRE 16 -1 (-1400 2000)(-1400 2175);
WIRE 16 -1 (-925 2175)(-1400 2175);
WIRE 16 -1 (-1900 2400)(-1900 2175);
WIRE 16 -1 (-1400 2175)(-1900 2175);
WIRE 16 -1 (-2200 2400)(-2200 2175);
WIRE 16 -1 (-1900 2175)(-2200 2175);
WIRE 16 -1 (-3350 2175)(-2200 2175);
FORCEPROP 2 LAST SIG_NAME H_CPU1_PROCHOT_G_N
J 0
(-3325 2186);
DISPLAY 0.617021 (-3325 2186);
PAINT ORANGE (-3325 2186);
WIRE 16 -1 (-1100 2000)(-1100 2300);
WIRE 16 -1 (-925 2300)(-1100 2300);
WIRE 16 -1 (-2475 2300)(-2475 2425);
WIRE 16 -1 (-1100 2300)(-2475 2300);
WIRE 16 -1 (-3350 2300)(-2750 2300);
WIRE 16 -1 (-2475 2300)(-2750 2300);
WIRE 16 -1 (-2750 2425)(-2750 2300);
FORCEPROP 2 LAST SIG_NAME H_CPU0_PROCHOT_G_N
J 0
(-3325 2311);
DISPLAY 0.617021 (-3325 2311);
PAINT ORANGE (-3325 2311);
WIRE 16 -1 (1675 2850)(1775 2850);
WIRE 16 -1 (1675 3250)(1675 2850);
WIRE 16 -1 (875 3250)(1675 3250);
FORCEPROP 2 LAST SIG_NAME FM_CPU0_PROCHOT_LVT3_R_N
J 0
(1000 3260);
DISPLAY 0.617021 (1000 3260);
PAINT ORANGE (1000 3260);
FORCEPROP 2 LASTPROP $XRERR UNIQUE?
J 0
(760 3260);
DISPLAY 0.638298 (760 3260);
PAINT MONO (760 3260);
DISPLAY INVISIBLE (760 3260);
WIRE 16 -1 (3050 3350)(3600 3350);
FORCEPROP 2 LAST SIG_NAME FM_CPU_ERR0_LVT3_N
J 0
(3125 3360);
DISPLAY 0.617021 (3125 3360);
PAINT ORANGE (3125 3360);
WIRE 16 -1 (2025 4425)(2025 3950);
WIRE 16 -1 (-1100 4425)(2025 4425);
FORCEPROP 2 LAST SIG_NAME H_CPU_ERR1_PCH_N
J 0
(440 4435);
DISPLAY 0.617021 (440 4435);
PAINT ORANGE (440 4435);
FORCEPROP 2 LASTPROP $XRERR UNIQUE?
J 0
(200 4435);
DISPLAY 0.638298 (200 4435);
PAINT MONO (200 4435);
DISPLAY INVISIBLE (200 4435);
WIRE 16 -1 (-1100 4225)(-1100 4425);
WIRE 16 -1 (-1375 4475)(-1375 4225);
WIRE 16 -1 (2400 4475)(-1375 4475);
FORCEPROP 2 LAST SIG_NAME H_CPU_ERR0_PCH_N
J 0
(440 4485);
DISPLAY 0.617021 (440 4485);
PAINT ORANGE (440 4485);
FORCEPROP 2 LASTPROP $XRERR UNIQUE?
J 0
(200 4485);
DISPLAY 0.638298 (200 4485);
PAINT MONO (200 4485);
DISPLAY INVISIBLE (200 4485);
WIRE 16 -1 (2400 3950)(2400 4475);
WIRE 16 -1 (1725 3100)(1775 3100);
WIRE 16 -1 (1725 3300)(1725 3100);
WIRE 16 -1 (875 3300)(1725 3300);
FORCEPROP 2 LAST SIG_NAME FM_CPU_ERR1_LVT3_R_N
J 0
(1000 3310);
DISPLAY 0.617021 (1000 3310);
PAINT ORANGE (1000 3310);
FORCEPROP 2 LASTPROP $XRERR UNIQUE?
J 0
(760 3310);
DISPLAY 0.638298 (760 3310);
PAINT MONO (760 3310);
DISPLAY INVISIBLE (760 3310);
WIRE 16 -1 (-825 3825)(-775 3825);
WIRE 16 -1 (-775 3825)(-775 3350);
WIRE 16 -1 (-25 3350)(-775 3350);
FORCEPROP 2 LAST SIG_NAME H_CPU_ERR0_GTL_N
J 0
(-575 3360);
DISPLAY 0.617021 (-575 3360);
PAINT ORANGE (-575 3360);
FORCEPROP 2 LASTPROP $XRERR UNIQUE?
J 0
(-815 3360);
DISPLAY 0.638298 (-815 3360);
PAINT MONO (-815 3360);
DISPLAY INVISIBLE (-815 3360);
WIRE 16 -1 (-25 3300)(-825 3300);
FORCEPROP 2 LAST SIG_NAME H_CPU_ERR1_GTL_N
J 0
(-500 3310);
DISPLAY 0.617021 (-500 3310);
PAINT ORANGE (-500 3310);
FORCEPROP 2 LASTPROP $XRERR UNIQUE?
J 0
(-740 3310);
DISPLAY 0.638298 (-740 3310);
PAINT MONO (-740 3310);
DISPLAY INVISIBLE (-740 3310);
WIRE 16 -1 (-1375 4025)(-1375 3825);
WIRE 16 -1 (-1025 3825)(-1375 3825);
WIRE 16 -1 (-2325 3950)(-2325 3825);
WIRE 16 -1 (-2325 3825)(-1375 3825);
WIRE 16 -1 (-2475 3725)(-2650 3725);
WIRE 16 -1 (-2475 3725)(-2475 3825);
WIRE 16 -1 (-2475 3825)(-2325 3825);
FORCEPROP 0 LAST SIG_NAME H_CPU_ERR0_GTL_R_N
J 0
(-2275 3835);
DISPLAY 0.617021 (-2275 3835);
PAINT ORANGE (-2275 3835);
FORCEPROP 2 LASTPROP $XRERR UNIQUE?
J 0
(-2515 3835);
DISPLAY 0.638298 (-2515 3835);
PAINT MONO (-2515 3835);
DISPLAY INVISIBLE (-2515 3835);
WIRE 16 -1 (-2650 3975)(-2475 3975);
WIRE 16 -1 (-2475 3975)(-2475 3825);
WIRE 16 -1 (-2125 1050)(-1375 1050);
FORCEPROP 2 LAST SIG_NAME FM_CPU_ERR1_LVT3_BMC_N
J 0
(-1975 1060);
DISPLAY 0.617021 (-1975 1060);
PAINT ORANGE (-1975 1060);
WIRE 16 -1 (-2125 850)(-1375 850);
FORCEPROP 2 LAST SIG_NAME FM_CPU_ERR1_PCH_N
J 0
(-1975 860);
DISPLAY 0.617021 (-1975 860);
PAINT ORANGE (-1975 860);
WIRE 16 2175 (-1975 -50)(-2475 -50);
WIRE 16 2175 (-1975 1625)(-1975 -50);
WIRE 16 2175 (-2475 -50)(-2475 1625);
WIRE 16 2175 (-2475 1625)(-1975 1625);
WIRE 16 -1 (-2125 275)(-1375 275);
FORCEPROP 2 LAST SIG_NAME FM_CPU1_PROCHOT_LVT3_BMC_N
J 0
(-1975 285);
DISPLAY 0.617021 (-1975 285);
PAINT ORANGE (-1975 285);
WIRE 16 -1 (-2125 1250)(-1375 1250);
FORCEPROP 2 LAST SIG_NAME FM_CPU_ERR0_PCH_N
J 0
(-1975 1260);
DISPLAY 0.617021 (-1975 1260);
PAINT ORANGE (-1975 1260);
WIRE 16 -1 (-2125 475)(-1375 475);
FORCEPROP 2 LAST SIG_NAME FM_CPU0_PROCHOT_PCH_N
J 0
(-1975 485);
DISPLAY 0.617021 (-1975 485);
PAINT ORANGE (-1975 485);
WIRE 16 -1 (-2125 75)(-1375 75);
FORCEPROP 2 LAST SIG_NAME FM_CPU1_PROCHOT_PCH_N
J 0
(-1975 85);
DISPLAY 0.617021 (-1975 85);
PAINT ORANGE (-1975 85);
WIRE 16 -1 (-2125 1450)(-1375 1450);
FORCEPROP 2 LAST SIG_NAME FM_CPU_ERR0_LVT3_BMC_N
J 0
(-1975 1460);
DISPLAY 0.617021 (-1975 1460);
PAINT ORANGE (-1975 1460);
WIRE 16 -1 (-3350 3200)(-2850 3200);
FORCEPROP 2 LAST SIG_NAME H_CPU1_ERR1_G_N
J 0
(-3325 3210);
DISPLAY 0.617021 (-3325 3210);
PAINT ORANGE (-3325 3210);
WIRE 16 -1 (-3350 3725)(-2850 3725);
FORCEPROP 2 LAST SIG_NAME H_CPU1_ERR0_G_N
J 0
(-3325 3735);
DISPLAY 0.617021 (-3325 3735);
PAINT ORANGE (-3325 3735);
WIRE 16 -1 (-3350 3425)(-2850 3425);
FORCEPROP 2 LAST SIG_NAME H_CPU0_ERR1_G_N
J 0
(-3325 3435);
DISPLAY 0.617021 (-3325 3435);
PAINT ORANGE (-3325 3435);
WIRE 16 -1 (-2325 1250)(-2550 1250);
WIRE 16 -1 (-2550 1250)(-2550 1450);
WIRE 16 -1 (-2550 1450)(-2325 1450);
WIRE 16 -1 (-3125 1450)(-2550 1450);
FORCEPROP 2 LAST SIG_NAME FM_CPU_ERR0_LVT3_N
J 0
(-3100 1460);
DISPLAY 0.617021 (-3100 1460);
PAINT ORANGE (-3100 1460);
WIRE 16 -1 (-2325 850)(-2550 850);
WIRE 16 -1 (-2550 850)(-2550 1050);
WIRE 16 -1 (-2550 1050)(-2325 1050);
WIRE 16 -1 (-3125 1050)(-2550 1050);
FORCEPROP 2 LAST SIG_NAME FM_CPU_ERR1_LVT3_N
J 0
(-3100 1060);
DISPLAY 0.617021 (-3100 1060);
PAINT ORANGE (-3100 1060);
WIRE 16 -1 (-2325 475)(-2550 475);
WIRE 16 -1 (-2550 475)(-2550 675);
WIRE 16 -1 (-2550 675)(-2325 675);
WIRE 16 -1 (-3125 675)(-2550 675);
FORCEPROP 2 LAST SIG_NAME FM_CPU0_PROCHOT_LVT3_N
J 0
(-3100 685);
DISPLAY 0.617021 (-3100 685);
PAINT ORANGE (-3100 685);
WIRE 16 -1 (-2325 75)(-2550 75);
WIRE 16 -1 (-2550 75)(-2550 275);
WIRE 16 -1 (-2550 275)(-2325 275);
WIRE 16 -1 (-3125 275)(-2550 275);
FORCEPROP 2 LAST SIG_NAME FM_CPU1_PROCHOT_LVT3_N
J 0
(-3100 285);
DISPLAY 0.617021 (-3100 285);
PAINT ORANGE (-3100 285);
WIRE 16 -1 (2400 3750)(2400 3350);
WIRE 16 -1 (2850 3350)(2400 3350);
WIRE 16 -1 (1975 3350)(2400 3350);
FORCEPROP 2 LAST SIG_NAME FM_CPU_ERR0_LVT3_K_N
J 0
(2090 3360);
DISPLAY 0.617021 (2090 3360);
PAINT ORANGE (2090 3360);
FORCEPROP 2 LASTPROP $XRERR UNIQUE?
J 0
(1850 3360);
DISPLAY 0.638298 (1850 3360);
PAINT MONO (1850 3360);
DISPLAY INVISIBLE (1850 3360);
WIRE 16 -1 (3050 3100)(3600 3100);
FORCEPROP 2 LAST SIG_NAME FM_CPU_ERR1_LVT3_N
J 0
(3125 3110);
DISPLAY 0.617021 (3125 3110);
PAINT ORANGE (3125 3110);
WIRE 16 -1 (3050 2575)(3600 2575);
FORCEPROP 2 LAST SIG_NAME FM_CPU1_PROCHOT_LVT3_N
J 0
(3125 2585);
DISPLAY 0.617021 (3125 2585);
PAINT ORANGE (3125 2585);
WIRE 16 -1 (3050 2850)(3600 2850);
FORCEPROP 2 LAST SIG_NAME FM_CPU0_PROCHOT_LVT3_N
J 0
(3125 2860);
DISPLAY 0.617021 (3125 2860);
PAINT ORANGE (3125 2860);
WIRE 16 -1 (2400 2325)(2400 2575);
WIRE 16 -1 (2850 2575)(2400 2575);
WIRE 16 -1 (1975 2575)(2400 2575);
FORCEPROP 2 LAST SIG_NAME FM_CPU1_PROCHOT_LVT3_K_N
J 0
(2115 2585);
DISPLAY 0.617021 (2115 2585);
PAINT ORANGE (2115 2585);
FORCEPROP 2 LASTPROP $XRERR UNIQUE?
J 0
(1875 2585);
DISPLAY 0.638298 (1875 2585);
PAINT MONO (1875 2585);
DISPLAY INVISIBLE (1875 2585);
WIRE 16 -1 (-725 2300)(-675 2300);
WIRE 16 -1 (-675 2300)(-675 3250);
WIRE 16 -1 (-25 3250)(-675 3250);
FORCEPROP 2 LAST SIG_NAME H_CPU0_PROCHOT_G_R_N
J 0
(-575 3260);
DISPLAY 0.617021 (-575 3260);
PAINT ORANGE (-575 3260);
FORCEPROP 2 LASTPROP $XRERR UNIQUE?
J 0
(-815 3260);
DISPLAY 0.638298 (-815 3260);
PAINT MONO (-815 3260);
DISPLAY INVISIBLE (-815 3260);
WIRE 16 -1 (-625 2175)(-725 2175);
WIRE 16 -1 (-625 3200)(-625 2175);
WIRE 16 -1 (-25 3200)(-625 3200);
FORCEPROP 2 LAST SIG_NAME H_CPU1_PROCHOT_G_R_N
J 0
(-575 3210);
DISPLAY 0.617021 (-575 3210);
PAINT ORANGE (-575 3210);
FORCEPROP 2 LASTPROP $XRERR UNIQUE?
J 0
(-815 3210);
DISPLAY 0.638298 (-815 3210);
PAINT MONO (-815 3210);
DISPLAY INVISIBLE (-815 3210);
DOT 1 (-100 300);
DOT 1 (1150 1300);
DOT 1 (-100 1400);
DOT 1 (2300 850);
DOT 1 (2300 800);
DOT 1 (1950 800);
DOT 1 (2300 350);
DOT 1 (-1400 2175);
DOT 1 (2025 2850);
DOT 1 (2025 3100);
DOT 1 (2400 3350);
DOT 1 (2400 2575);
DOT 1 (1000 4050);
DOT 1 (-2325 4225);
DOT 1 (-200 3000);
DOT 1 (-200 2950);
DOT 1 (-1375 3825);
DOT 1 (-1100 3300);
DOT 1 (-2025 3300);
DOT 1 (-1100 2300);
DOT 1 (-1900 2175);
DOT 1 (-450 1300);
DOT 1 (-2325 3825);
DOT 1 (-2475 3825);
DOT 1 (-2475 3300);
DOT 1 (-2200 2700);
DOT 1 (-2200 2175);
DOT 1 (-2475 2300);
DOT 1 (-2750 2725);
DOT 1 (-2750 2300);
DOT 1 (-2550 1450);
DOT 1 (-2550 1050);
DOT 1 (-2550 675);
DOT 1 (-2550 275);
FORCENOTE
TP FAB3 CHANGE R2T36 AND CONNECT TO P3V3  0803
(2325 850) 0;
DISPLAY LEFT (2325 850);
DISPLAY 1.021277 (2325 850);
PAINT RED (2325 850);
FORCENOTE
WITH 20 OHM RESISTOR G21976-173
(-75 325) 0;
DISPLAY LEFT (-75 325);
DISPLAY 1.021277 (-75 325);
PAINT PURPLE (-75 325);
FORCENOTE
STUFF R2T17, R2T20, R2T32, & R2T27
(-75 400) 0;
DISPLAY LEFT (-75 400);
DISPLAY 1.021277 (-75 400);
PAINT PURPLE (-75 400);
FORCENOTE
TP FAB3 ADD R2W2 0803
(1500 850) 0;
DISPLAY LEFT (1500 850);
DISPLAY 0.808511 (1500 850);
PAINT RED (1500 850);
FORCENOTE
R1T35
(-75 550) 0;
DISPLAY LEFT (-75 550);
DISPLAY 1.021277 (-75 550);
PAINT PURPLE (-75 550);
FORCENOTE
R1T38
(-75 475) 0;
DISPLAY LEFT (-75 475);
DISPLAY 1.021277 (-75 475);
PAINT PURPLE (-75 475);
FORCENOTE
R2T58
(-75 775) 0;
DISPLAY LEFT (-75 775);
DISPLAY 1.021277 (-75 775);
PAINT PURPLE (-75 775);
FORCENOTE
R2T65
(-400 850) 0;
DISPLAY LEFT (-400 850);
DISPLAY 1.021277 (-400 850);
PAINT PURPLE (-400 850);
FORCENOTE
R2T62
(-75 925) 0;
DISPLAY LEFT (-75 925);
DISPLAY 1.021277 (-75 925);
PAINT PURPLE (-75 925);
FORCENOTE
R2T71
(-75 850) 0;
DISPLAY LEFT (-75 850);
DISPLAY 1.021277 (-75 850);
PAINT PURPLE (-75 850);
FORCENOTE
R8F37
(-75 700) 0;
DISPLAY LEFT (-75 700);
DISPLAY 1.021277 (-75 700);
PAINT PURPLE (-75 700);
FORCENOTE
R2T63
(-75 625) 0;
DISPLAY LEFT (-75 625);
DISPLAY 1.021277 (-75 625);
PAINT PURPLE (-75 625);
FORCENOTE
TARGET 0.7V
(2625 900) 0;
DISPLAY LEFT (2625 900);
DISPLAY 1.021277 (2625 900);
PAINT PURPLE (2625 900);
FORCENOTE
R7D41
(-400 625) 0;
DISPLAY LEFT (-400 625);
DISPLAY 1.021277 (-400 625);
PAINT PURPLE (-400 625);
FORCENOTE
R2T66
(-400 775) 0;
DISPLAY LEFT (-400 775);
DISPLAY 1.021277 (-400 775);
PAINT PURPLE (-400 775);
FORCENOTE
R2T68
(-400 925) 0;
DISPLAY LEFT (-400 925);
DISPLAY 1.021277 (-400 925);
PAINT PURPLE (-400 925);
FORCENOTE
R2T59
(-75 1000) 0;
DISPLAY LEFT (-75 1000);
DISPLAY 1.021277 (-75 1000);
PAINT PURPLE (-75 1000);
FORCENOTE
IE ONLY (NO BMC)
(-425 1425) 0;
DISPLAY LEFT (-425 1425);
DISPLAY 1.021277 (-425 1425);
PAINT PURPLE (-425 1425);
FORCENOTE
R2T69
(-75 1150) 0;
DISPLAY LEFT (-75 1150);
DISPLAY 1.021277 (-75 1150);
PAINT PURPLE (-75 1150);
FORCENOTE
R2T57
(-75 1225) 0;
DISPLAY LEFT (-75 1225);
DISPLAY 1.021277 (-75 1225);
PAINT PURPLE (-75 1225);
FORCENOTE
STUFF
(-75 1325) 0;
DISPLAY LEFT (-75 1325);
DISPLAY 1.021277 (-75 1325);
PAINT PURPLE (-75 1325);
FORCENOTE
R2T61
(-75 1075) 0;
DISPLAY LEFT (-75 1075);
DISPLAY 1.021277 (-75 1075);
PAINT PURPLE (-75 1075);
FORCENOTE
R2T31
(-400 1075) 0;
DISPLAY LEFT (-400 1075);
DISPLAY 1.021277 (-400 1075);
PAINT PURPLE (-400 1075);
FORCENOTE
R2T16
(-400 1150) 0;
DISPLAY LEFT (-400 1150);
DISPLAY 1.021277 (-400 1150);
PAINT PURPLE (-400 1150);
FORCENOTE
UNSTUFF
(-425 1325) 0;
DISPLAY LEFT (-425 1325);
DISPLAY 1.021277 (-425 1325);
PAINT PURPLE (-425 1325);
FORCENOTE
U2T4
(-400 1225) 0;
DISPLAY LEFT (-400 1225);
DISPLAY 1.021277 (-400 1225);
PAINT PURPLE (-400 1225);
FORCENOTE
R2T60
(-400 1000) 0;
DISPLAY LEFT (-400 1000);
DISPLAY 1.021277 (-400 1000);
PAINT PURPLE (-400 1000);
FORCENOTE
R2T67
(-400 700) 0;
DISPLAY LEFT (-400 700);
DISPLAY 1.021277 (-400 700);
PAINT PURPLE (-400 700);
FORCENOTE
R8F38
(-400 550) 0;
DISPLAY LEFT (-400 550);
DISPLAY 1.021277 (-400 550);
PAINT PURPLE (-400 550);
FORCENOTE
R2T64
(-400 475) 0;
DISPLAY LEFT (-400 475);
DISPLAY 1.021277 (-400 475);
PAINT PURPLE (-400 475);
FORCENOTE
R1T37
(-400 325) 0;
DISPLAY LEFT (-400 325);
DISPLAY 1.021277 (-400 325);
PAINT PURPLE (-400 325);
FORCENOTE
R1T36
(-400 400) 0;
DISPLAY LEFT (-400 400);
DISPLAY 1.021277 (-400 400);
PAINT PURPLE (-400 400);
FORCENOTE
ROOM=PROC_SIDEBAND
(-3721 -157) 0;
DISPLAY LEFT (-3721 -157);
DISPLAY 1.595745 (-3721 -157);
PAINT PURPLE (-3721 -157);
QUIT
